FILE_TYPE = MACRO_DRAWING;
SET COLOR_WIRE YELLOW;
SET COLOR_PROP ORANGE;
SET COLOR_DOT WHITE;
SET COLOR_ARC YELLOW;
SET COLOR_BODY GREEN;
SET COLOR_NOTE PURPLE;
SET PROP_DISPLAY VALUE;
SET PAGE_NUMBER P182;
FORCEADD VCC_CORE..1
(-7650 950);
FORCEPROP 3 LASTPIN (-7650 900) SIG_NAME P5V_AUX\g
J 0
(-7640 910);
DISPLAY 0.659574 (-7640 910);
PAINT MONO (-7640 910);
DISPLAY INVISIBLE (-7640 910);
FORCEPROP 1 LAST HDL_POWER P5V_AUX
J 1
(-7650 1000);
DISPLAY 0.489362 (-7650 1000);
PAINT GREEN (-7650 1000);
FORCEPROP 2 LAST CDS_LIB pure_quanta_power
J 0
(-7650 950);
DISPLAY INVISIBLE (-7650 950);
FORCEPROP 1 LAST PATH I1
J 0
(-7600 975);
DISPLAY 0.872340 (-7600 975);
PAINT AQUA (-7600 975);
DISPLAY INVISIBLE (-7600 975);
FORCEADD OFFPAGE..4
R 2
(-7575 3825);
FORCEPROP 2 LAST $XR0 27 
J 0
(-7916 3825);
DISPLAY 0.638298 (-7916 3825);
PAINT MONO (-7916 3825);
FORCEPROP 2 LAST $XR1 200 
J 0
(-8036 3825);
DISPLAY 0.638298 (-8036 3825);
PAINT MONO (-8036 3825);
FORCEPROP 2 LAST CDS_LIB standard
J 0
(-7575 3825);
DISPLAY INVISIBLE (-7575 3825);
FORCEPROP 1 LAST OFFPAGE TRUE
J 2
(-7900 3700);
DISPLAY 0.872340 (-7900 3700);
PAINT GREEN (-7900 3700);
DISPLAY INVISIBLE (-7900 3700);
FORCEPROP 1 LAST COMMENT_BODY TRUE
J 2
(-7550 3725);
DISPLAY 0.872340 (-7550 3725);
PAINT GREEN (-7550 3725);
DISPLAY INVISIBLE (-7550 3725);
FORCEPROP 2 LAST PATH I10
J 0
(-7900 3875);
DISPLAY 0.680851 (-7900 3875);
DISPLAY INVISIBLE (-7900 3875);
FORCEADD OFFPAGE..4
R 2
(-7575 4075);
FORCEPROP 2 LAST $XR0 27 
J 0
(-7916 4075);
DISPLAY 0.638298 (-7916 4075);
PAINT MONO (-7916 4075);
FORCEPROP 2 LAST CDS_LIB standard
J 2
(-7575 4075);
DISPLAY INVISIBLE (-7575 4075);
FORCEPROP 1 LAST OFFPAGE TRUE
J 2
(-7900 3950);
DISPLAY 0.872340 (-7900 3950);
PAINT GREEN (-7900 3950);
DISPLAY INVISIBLE (-7900 3950);
FORCEPROP 1 LAST COMMENT_BODY TRUE
J 2
(-7550 3975);
DISPLAY 0.872340 (-7550 3975);
PAINT GREEN (-7550 3975);
DISPLAY INVISIBLE (-7550 3975);
FORCEPROP 2 LAST PATH I11
J 0
(-7900 4125);
DISPLAY 0.680851 (-7900 4125);
DISPLAY INVISIBLE (-7900 4125);
FORCEADD OFFPAGE..2
R 2
(-7025 2125);
FORCEPROP 2 LAST $XR0 82 
J 0
(-7249 2125);
DISPLAY 0.638298 (-7249 2125);
PAINT MONO (-7249 2125);
FORCEPROP 2 LAST CDS_LIB standard
J 0
(-7025 2125);
DISPLAY INVISIBLE (-7025 2125);
FORCEPROP 1 LAST OFFPAGE TRUE
J 2
(-7350 2000);
DISPLAY 0.872340 (-7350 2000);
PAINT GREEN (-7350 2000);
DISPLAY INVISIBLE (-7350 2000);
FORCEPROP 1 LAST COMMENT_BODY TRUE
J 2
(-6980 2030);
DISPLAY 0.872340 (-6980 2030);
PAINT GREEN (-6980 2030);
DISPLAY INVISIBLE (-6980 2030);
FORCEPROP 2 LAST PATH I12
J 0
(-7275 2175);
DISPLAY 0.680851 (-7275 2175);
DISPLAY INVISIBLE (-7275 2175);
FORCEADD Q_RES..1
(-6275 2125);
FORCEPROP 1 LAST LOCATION R8116
J 0
(-6325 2175);
DISPLAY 0.489362 (-6325 2175);
PAINT SKYBLUE (-6325 2175);
FORCEPROP 0 LAST $SEC 1
J 0
(-6325 2225);
DISPLAY 0.680851 (-6325 2225);
PAINT MONO (-6325 2225);
DISPLAY INVISIBLE (-6325 2225);
FORCEPROP 0 LAST CDS_SEC 1
J 0
(-6325 2225);
DISPLAY 1.021277 (-6325 2225);
DISPLAY INVISIBLE (-6325 2225);
FORCEPROP 1 LASTPIN (-6375 2125) $PN 1
J 0
(-6363 2137);
DISPLAY 0.489362 (-6363 2137);
PAINT MONO (-6363 2137);
FORCEPROP 1 LASTPIN (-6175 2125) $PN 2
J 0
(-6213 2137);
DISPLAY 0.489362 (-6213 2137);
PAINT MONO (-6213 2137);
FORCEPROP 1 LAST VALUE 0
J 2
(-6400 2150);
DISPLAY 0.489362 (-6400 2150);
PAINT SKYBLUE (-6400 2150);
FORCEPROP 1 LAST TOLERANCE 5%
J 0
(-6150 2150);
DISPLAY 0.489362 (-6150 2150);
PAINT SKYBLUE (-6150 2150);
FORCEPROP 1 LAST WATTAGE 1/16W
J 0
(-6175 2075);
DISPLAY 0.489362 (-6175 2075);
PAINT SKYBLUE (-6175 2075);
FORCEPROP 1 LAST PACK_TYPE 0402LF
J 0
(-6175 2050);
DISPLAY 0.489362 (-6175 2050);
PAINT SKYBLUE (-6175 2050);
FORCEPROP 1 LAST MATERIAL EMPTY
J 0
(-6525 2050);
DISPLAY 0.489362 (-6525 2050);
PAINT RED (-6525 2050);
FORCEPROP 2 LAST CDS_LIB pure_quanta
J 0
(-6275 2125);
DISPLAY INVISIBLE (-6275 2125);
FORCEPROP 1 LAST PATH I13
J 0
(-6325 2275);
DISPLAY 0.978723 (-6325 2275);
PAINT WHITE (-6325 2275);
DISPLAY INVISIBLE (-6325 2275);
FORCEPROP 1 LAST PART_NUMBER CS00002JB13
J 0
(-6525 2075);
DISPLAY 0.489362 (-6525 2075);
PAINT SKYBLUE (-6525 2075);
DISPLAY INVISIBLE (-6525 2075);
FORCEADD UNIVERSAL_GND..1
(-6900 3500);
FORCEPROP 3 LASTPIN (-6900 3550) SIG_NAME GND\g
J 0
(-6890 3560);
DISPLAY 0.659574 (-6890 3560);
PAINT MONO (-6890 3560);
DISPLAY INVISIBLE (-6890 3560);
FORCEPROP 2 LAST CDS_LIB pure_quanta_power
J 0
(-6900 3500);
DISPLAY INVISIBLE (-6900 3500);
FORCEPROP 1 LAST HDL_POWER GND
J 1
(-6875 3425);
DISPLAY 0.872340 (-6875 3425);
PAINT GREEN (-6875 3425);
DISPLAY INVISIBLE (-6875 3425);
FORCEPROP 1 LAST PATH I14
J 0
(-6825 3500);
DISPLAY 0.872340 (-6825 3500);
PAINT AQUA (-6825 3500);
DISPLAY INVISIBLE (-6825 3500);
FORCEADD Q_RES..2
(-6900 3675);
FORCEPROP 1 LAST LOCATION PR115
J 0
(-6850 3800);
DISPLAY 0.489362 (-6850 3800);
PAINT SKYBLUE (-6850 3800);
FORCEPROP 0 LAST $SEC 1
J 0
(-6850 3825);
DISPLAY 0.680851 (-6850 3825);
PAINT MONO (-6850 3825);
DISPLAY INVISIBLE (-6850 3825);
FORCEPROP 0 LAST CDS_SEC 1
J 0
(-6850 3825);
DISPLAY 1.021277 (-6850 3825);
DISPLAY INVISIBLE (-6850 3825);
FORCEPROP 1 LASTPIN (-6900 3775) $PN 1
J 0
(-6895 3737);
DISPLAY 0.489362 (-6895 3737);
PAINT MONO (-6895 3737);
FORCEPROP 1 LASTPIN (-6900 3575) $PN 2
J 0
(-6895 3585);
DISPLAY 0.489362 (-6895 3585);
PAINT MONO (-6895 3585);
FORCEPROP 1 LAST MATERIAL CHIP
J 0
(-6850 3600);
DISPLAY 0.489362 (-6850 3600);
PAINT SKYBLUE (-6850 3600);
FORCEPROP 1 LAST WATTAGE 1/16W
J 0
(-6850 3650);
DISPLAY 0.489362 (-6850 3650);
PAINT SKYBLUE (-6850 3650);
FORCEPROP 1 LAST VALUE 49.9
J 0
(-6850 3750);
DISPLAY 0.489362 (-6850 3750);
PAINT SKYBLUE (-6850 3750);
FORCEPROP 1 LAST TOLERANCE 1%
J 0
(-6850 3700);
DISPLAY 0.489362 (-6850 3700);
PAINT SKYBLUE (-6850 3700);
FORCEPROP 1 LAST PACK_TYPE 0402LF
J 0
(-6850 3500);
DISPLAY 0.489362 (-6850 3500);
PAINT SKYBLUE (-6850 3500);
FORCEPROP 2 LAST CDS_LIB pure_quanta
J 0
(-6900 3675);
DISPLAY INVISIBLE (-6900 3675);
FORCEPROP 1 LAST PATH I15
J 0
(-6850 3850);
DISPLAY 0.978723 (-6850 3850);
PAINT WHITE (-6850 3850);
DISPLAY INVISIBLE (-6850 3850);
FORCEPROP 1 LAST PART_NUMBER CS04992FB07
J 0
(-6850 3550);
DISPLAY 0.489362 (-6850 3550);
PAINT SKYBLUE (-6850 3550);
DISPLAY INVISIBLE (-6850 3550);
FORCEADD Q_RES..1
(-6050 675);
FORCEPROP 1 LAST LOCATION PR125
J 0
(-6075 725);
DISPLAY 0.489362 (-6075 725);
PAINT SKYBLUE (-6075 725);
FORCEPROP 0 LAST $SEC 1
J 0
(-6100 775);
DISPLAY 0.680851 (-6100 775);
PAINT MONO (-6100 775);
DISPLAY INVISIBLE (-6100 775);
FORCEPROP 0 LAST CDS_SEC 1
J 0
(-6100 775);
DISPLAY 1.021277 (-6100 775);
DISPLAY INVISIBLE (-6100 775);
FORCEPROP 1 LASTPIN (-6150 675) $PN 1
J 0
(-6138 687);
DISPLAY 0.489362 (-6138 687);
PAINT MONO (-6138 687);
FORCEPROP 1 LASTPIN (-5950 675) $PN 2
J 0
(-5988 687);
DISPLAY 0.489362 (-5988 687);
PAINT MONO (-5988 687);
FORCEPROP 1 LAST MATERIAL CHIP
J 0
(-6300 600);
DISPLAY 0.489362 (-6300 600);
PAINT SKYBLUE (-6300 600);
FORCEPROP 1 LAST PACK_TYPE 0402LF
J 0
(-5950 600);
DISPLAY 0.489362 (-5950 600);
PAINT SKYBLUE (-5950 600);
FORCEPROP 1 LAST WATTAGE 1/16W
J 0
(-5950 625);
DISPLAY 0.489362 (-5950 625);
PAINT SKYBLUE (-5950 625);
FORCEPROP 1 LAST TOLERANCE 5%
J 0
(-5925 700);
DISPLAY 0.489362 (-5925 700);
PAINT SKYBLUE (-5925 700);
FORCEPROP 1 LAST VALUE 0
J 2
(-6175 700);
DISPLAY 0.489362 (-6175 700);
PAINT SKYBLUE (-6175 700);
FORCEPROP 2 LAST CDS_LIB pure_quanta
J 0
(-6050 675);
DISPLAY INVISIBLE (-6050 675);
FORCEPROP 1 LAST PATH I16
J 0
(-6100 825);
DISPLAY 0.978723 (-6100 825);
PAINT WHITE (-6100 825);
DISPLAY INVISIBLE (-6100 825);
FORCEPROP 1 LAST PART_NUMBER CS00002JB13
J 0
(-6300 625);
DISPLAY 0.489362 (-6300 625);
PAINT SKYBLUE (-6300 625);
DISPLAY INVISIBLE (-6300 625);
FORCEADD UNIVERSAL_GND..1
(-5725 275);
FORCEPROP 3 LASTPIN (-5725 325) SIG_NAME GND\g
J 0
(-5715 335);
DISPLAY 0.659574 (-5715 335);
PAINT MONO (-5715 335);
DISPLAY INVISIBLE (-5715 335);
FORCEPROP 2 LAST CDS_LIB pure_quanta_power
J 0
(-5725 275);
DISPLAY INVISIBLE (-5725 275);
FORCEPROP 1 LAST HDL_POWER GND
J 1
(-5700 200);
DISPLAY 0.872340 (-5700 200);
PAINT GREEN (-5700 200);
DISPLAY INVISIBLE (-5700 200);
FORCEPROP 1 LAST PATH I17
J 0
(-5650 275);
DISPLAY 0.872340 (-5650 275);
PAINT AQUA (-5650 275);
DISPLAY INVISIBLE (-5650 275);
FORCEADD Q_RES..2
(-5725 475);
FORCEPROP 1 LAST LOCATION PR601
J 0
(-5675 600);
DISPLAY 0.489362 (-5675 600);
PAINT SKYBLUE (-5675 600);
FORCEPROP 0 LAST $SEC 1
J 0
(-5675 625);
DISPLAY 0.680851 (-5675 625);
PAINT MONO (-5675 625);
DISPLAY INVISIBLE (-5675 625);
FORCEPROP 0 LAST CDS_SEC 1
J 0
(-5675 625);
DISPLAY 0.680851 (-5675 625);
DISPLAY INVISIBLE (-5675 625);
FORCEPROP 1 LASTPIN (-5725 575) $PN 1
J 0
(-5720 537);
DISPLAY 0.787234 (-5720 537);
PAINT MONO (-5720 537);
DISPLAY INVISIBLE (-5720 537);
FORCEPROP 1 LASTPIN (-5725 375) $PN 2
J 0
(-5720 385);
DISPLAY 0.787234 (-5720 385);
PAINT MONO (-5720 385);
DISPLAY INVISIBLE (-5720 385);
FORCEPROP 1 LAST WATTAGE 1/16W
J 0
(-5675 450);
DISPLAY 0.489362 (-5675 450);
PAINT SKYBLUE (-5675 450);
FORCEPROP 1 LAST MATERIAL EMPTY
J 0
(-5675 400);
DISPLAY 0.489362 (-5675 400);
PAINT RED (-5675 400);
FORCEPROP 1 LAST TOLERANCE 1%
J 0
(-5675 500);
DISPLAY 0.489362 (-5675 500);
PAINT SKYBLUE (-5675 500);
FORCEPROP 1 LAST VALUE 4.99K
J 0
(-5675 550);
DISPLAY 0.489362 (-5675 550);
PAINT SKYBLUE (-5675 550);
FORCEPROP 1 LAST PACK_TYPE 0402LF
J 0
(-5675 300);
DISPLAY 0.489362 (-5675 300);
PAINT SKYBLUE (-5675 300);
FORCEPROP 2 LAST CDS_LIB pure_quanta
J 0
(-5725 475);
DISPLAY INVISIBLE (-5725 475);
FORCEPROP 1 LAST PATH I18
J 0
(-5675 650);
DISPLAY 0.978723 (-5675 650);
PAINT WHITE (-5675 650);
DISPLAY INVISIBLE (-5675 650);
FORCEPROP 1 LAST PART_NUMBER CS24992FB07
J 0
(-5675 350);
DISPLAY 0.489362 (-5675 350);
PAINT SKYBLUE (-5675 350);
DISPLAY INVISIBLE (-5675 350);
FORCEADD UNIVERSAL_GND..1
(-5400 275);
FORCEPROP 3 LASTPIN (-5400 325) SIG_NAME GND\g
J 0
(-5390 335);
DISPLAY 0.659574 (-5390 335);
PAINT MONO (-5390 335);
DISPLAY INVISIBLE (-5390 335);
FORCEPROP 2 LAST CDS_LIB pure_quanta_power
J 0
(-5400 275);
DISPLAY INVISIBLE (-5400 275);
FORCEPROP 1 LAST HDL_POWER GND
J 1
(-5375 200);
DISPLAY 0.872340 (-5375 200);
PAINT GREEN (-5375 200);
DISPLAY INVISIBLE (-5375 200);
FORCEPROP 1 LAST PATH I19
J 0
(-5325 275);
DISPLAY 0.872340 (-5325 275);
PAINT AQUA (-5325 275);
DISPLAY INVISIBLE (-5325 275);
FORCEADD Q_RES..1
(-7300 850);
FORCEPROP 1 LAST LOCATION PR113
J 0
(-7350 900);
DISPLAY 0.489362 (-7350 900);
PAINT SKYBLUE (-7350 900);
FORCEPROP 0 LAST $SEC 1
J 0
(-7350 950);
DISPLAY 0.680851 (-7350 950);
PAINT MONO (-7350 950);
DISPLAY INVISIBLE (-7350 950);
FORCEPROP 0 LAST CDS_SEC 1
J 0
(-7350 950);
DISPLAY 1.021277 (-7350 950);
DISPLAY INVISIBLE (-7350 950);
FORCEPROP 1 LASTPIN (-7400 850) $PN 1
J 0
(-7388 862);
DISPLAY 0.489362 (-7388 862);
PAINT MONO (-7388 862);
FORCEPROP 1 LASTPIN (-7200 850) $PN 2
J 0
(-7238 862);
DISPLAY 0.489362 (-7238 862);
PAINT MONO (-7238 862);
FORCEPROP 1 LAST WATTAGE 1/16W
J 0
(-7175 800);
DISPLAY 0.489362 (-7175 800);
PAINT SKYBLUE (-7175 800);
FORCEPROP 1 LAST TOLERANCE 1%
J 0
(-7150 875);
DISPLAY 0.489362 (-7150 875);
PAINT SKYBLUE (-7150 875);
FORCEPROP 1 LAST PACK_TYPE 0402LF
J 0
(-7175 775);
DISPLAY 0.489362 (-7175 775);
PAINT SKYBLUE (-7175 775);
FORCEPROP 1 LAST MATERIAL CHIP
J 0
(-7600 775);
DISPLAY 0.489362 (-7600 775);
PAINT SKYBLUE (-7600 775);
FORCEPROP 1 LAST VALUE 40.2K
J 2
(-7450 875);
DISPLAY 0.489362 (-7450 875);
PAINT SKYBLUE (-7450 875);
FORCEPROP 2 LAST CDS_LIB pure_quanta
J 0
(-7300 850);
DISPLAY INVISIBLE (-7300 850);
FORCEPROP 1 LAST PATH I2
J 0
(-7350 1000);
DISPLAY 0.978723 (-7350 1000);
PAINT WHITE (-7350 1000);
DISPLAY INVISIBLE (-7350 1000);
FORCEPROP 1 LAST PART_NUMBER CS34022FB04
J 0
(-7600 800);
DISPLAY 0.489362 (-7600 800);
PAINT SKYBLUE (-7600 800);
DISPLAY INVISIBLE (-7600 800);
FORCEADD Q_CAP..1
(-5400 500);
FORCEPROP 1 LAST LOCATION PC5
J 0
(-5350 600);
DISPLAY 0.489362 (-5350 600);
PAINT SKYBLUE (-5350 600);
FORCEPROP 2 LAST SEC 1
J 0
(-5350 700);
DISPLAY 0.680851 (-5350 700);
PAINT MONO (-5350 700);
DISPLAY INVISIBLE (-5350 700);
FORCEPROP 1 LASTPIN (-5400 600) $PN 1
J 0
(-5390 580);
DISPLAY 0.489362 (-5390 580);
PAINT MONO (-5390 580);
FORCEPROP 1 LASTPIN (-5400 400) $PN 2
J 0
(-5390 380);
DISPLAY 0.489362 (-5390 380);
PAINT MONO (-5390 380);
FORCEPROP 1 LAST PACK_TYPE 0402
J 0
(-5350 300);
DISPLAY 0.489362 (-5350 300);
PAINT SKYBLUE (-5350 300);
FORCEPROP 1 LAST VOLTAGE 25V
J 0
(-5350 500);
DISPLAY 0.489362 (-5350 500);
PAINT SKYBLUE (-5350 500);
FORCEPROP 1 LAST VALUE 0.1UF
J 0
(-5350 550);
DISPLAY 0.489362 (-5350 550);
PAINT SKYBLUE (-5350 550);
FORCEPROP 1 LAST TOLERANCE 10%
J 0
(-5350 450);
DISPLAY 0.489362 (-5350 450);
PAINT SKYBLUE (-5350 450);
FORCEPROP 1 LAST MATERIAL X7R
J 0
(-5350 400);
DISPLAY 0.489362 (-5350 400);
PAINT SKYBLUE (-5350 400);
FORCEPROP 2 LAST CDS_LIB pure_quanta
J 0
(-5400 500);
DISPLAY INVISIBLE (-5400 500);
FORCEPROP 2 LAST SEC_TYPE 0402
J 0
(-5350 700);
DISPLAY 1.021277 (-5350 700);
DISPLAY INVISIBLE (-5350 700);
FORCEPROP 1 LAST PATH I20
J 0
(-5350 650);
DISPLAY 0.978723 (-5350 650);
PAINT WHITE (-5350 650);
DISPLAY INVISIBLE (-5350 650);
FORCEPROP 1 LAST PART_NUMBER CH4104K1B00
J 0
(-5350 350);
DISPLAY 0.489362 (-5350 350);
PAINT SKYBLUE (-5350 350);
DISPLAY INVISIBLE (-5350 350);
FORCEADD UNIVERSAL_GND..1
(-5700 1075);
FORCEPROP 3 LASTPIN (-5700 1125) SIG_NAME GND\g
J 0
(-5690 1135);
DISPLAY 0.659574 (-5690 1135);
PAINT MONO (-5690 1135);
DISPLAY INVISIBLE (-5690 1135);
FORCEPROP 2 LAST CDS_LIB pure_quanta_power
J 0
(-5700 1075);
DISPLAY INVISIBLE (-5700 1075);
FORCEPROP 1 LAST HDL_POWER GND
J 1
(-5675 1000);
DISPLAY 0.872340 (-5675 1000);
PAINT GREEN (-5675 1000);
DISPLAY INVISIBLE (-5675 1000);
FORCEPROP 1 LAST PATH I21
J 0
(-5625 1075);
DISPLAY 0.872340 (-5625 1075);
PAINT AQUA (-5625 1075);
DISPLAY INVISIBLE (-5625 1075);
FORCEADD Q_RES..2
(-5700 1275);
FORCEPROP 1 LAST LOCATION PR126
J 0
(-5650 1325);
DISPLAY 0.489362 (-5650 1325);
PAINT SKYBLUE (-5650 1325);
FORCEPROP 0 LAST $SEC 1
J 0
(-5650 1350);
DISPLAY 0.680851 (-5650 1350);
PAINT MONO (-5650 1350);
DISPLAY INVISIBLE (-5650 1350);
FORCEPROP 0 LAST CDS_SEC 1
J 0
(-5650 1350);
DISPLAY 1.021277 (-5650 1350);
DISPLAY INVISIBLE (-5650 1350);
FORCEPROP 1 LASTPIN (-5700 1375) $PN 1
J 0
(-5695 1337);
DISPLAY 0.489362 (-5695 1337);
PAINT MONO (-5695 1337);
FORCEPROP 1 LASTPIN (-5700 1175) $PN 2
J 0
(-5695 1185);
DISPLAY 0.489362 (-5695 1185);
PAINT MONO (-5695 1185);
FORCEPROP 1 LAST PACK_TYPE 0402LF
J 0
(-5650 1175);
DISPLAY 0.489362 (-5650 1175);
PAINT SKYBLUE (-5650 1175);
FORCEPROP 1 LAST MATERIAL CHIP
J 0
(-5650 1225);
DISPLAY 0.489362 (-5650 1225);
PAINT SKYBLUE (-5650 1225);
FORCEPROP 1 LAST TOLERANCE 1%
J 0
(-5650 1275);
DISPLAY 0.489362 (-5650 1275);
PAINT SKYBLUE (-5650 1275);
FORCEPROP 1 LAST VALUE 3.09K
J 0
(-5650 1300);
DISPLAY 0.489362 (-5650 1300);
PAINT SKYBLUE (-5650 1300);
FORCEPROP 1 LAST WATTAGE 1/16W
J 0
(-5650 1250);
DISPLAY 0.489362 (-5650 1250);
PAINT SKYBLUE (-5650 1250);
FORCEPROP 2 LAST CDS_LIB pure_quanta
J 0
(-5700 1275);
DISPLAY INVISIBLE (-5700 1275);
FORCEPROP 1 LAST PATH I22
J 0
(-5650 1450);
DISPLAY 0.978723 (-5650 1450);
PAINT WHITE (-5650 1450);
DISPLAY INVISIBLE (-5650 1450);
FORCEPROP 1 LAST PART_NUMBER CS23092FB04
J 0
(-5650 1200);
DISPLAY 0.489362 (-5650 1200);
PAINT SKYBLUE (-5650 1200);
DISPLAY INVISIBLE (-5650 1200);
FORCEADD UNIVERSAL_GND..1
(-5200 475);
FORCEPROP 3 LASTPIN (-5200 525) SIG_NAME GND\g
J 0
(-5190 535);
DISPLAY 0.659574 (-5190 535);
PAINT MONO (-5190 535);
DISPLAY INVISIBLE (-5190 535);
FORCEPROP 2 LAST CDS_LIB pure_quanta_power
J 0
(-5200 475);
DISPLAY INVISIBLE (-5200 475);
FORCEPROP 1 LAST HDL_POWER GND
J 1
(-5175 400);
DISPLAY 0.872340 (-5175 400);
PAINT GREEN (-5175 400);
DISPLAY INVISIBLE (-5175 400);
FORCEPROP 1 LAST PATH I23
J 0
(-5125 475);
DISPLAY 0.872340 (-5125 475);
PAINT AQUA (-5125 475);
DISPLAY INVISIBLE (-5125 475);
FORCEADD RAA229621GNPHA0..1
(-4425 3375);
FORCEPROP 1 LAST LOCATION PU21
J 0
(-4975 6400);
DISPLAY 0.489362 (-4975 6400);
PAINT SKYBLUE (-4975 6400);
FORCEPROP 0 LAST $SEC 1
J 0
(-4950 6575);
DISPLAY 0.680851 (-4950 6575);
PAINT MONO (-4950 6575);
DISPLAY INVISIBLE (-4950 6575);
FORCEPROP 0 LAST CDS_SEC 1
J 0
(-4950 6575);
DISPLAY 1.021277 (-4950 6575);
DISPLAY INVISIBLE (-4950 6575);
FORCEPROP 0 LASTPIN (-3775 1875) $PN 30
J 0
(-3765 1885);
DISPLAY 0.489362 (-3765 1885);
PAINT MONO (-3765 1885);
FORCEPROP 0 LASTPIN (-3775 2325) $PN 29
J 0
(-3765 2335);
DISPLAY 0.489362 (-3765 2335);
PAINT MONO (-3765 2335);
FORCEPROP 0 LASTPIN (-3775 2775) $PN 28
J 0
(-3765 2785);
DISPLAY 0.489362 (-3765 2785);
PAINT MONO (-3765 2785);
FORCEPROP 0 LASTPIN (-3775 3225) $PN 27
J 0
(-3765 3235);
DISPLAY 0.489362 (-3765 3235);
PAINT MONO (-3765 3235);
FORCEPROP 0 LASTPIN (-3775 3675) $PN 26
J 0
(-3765 3685);
DISPLAY 0.489362 (-3765 3685);
PAINT MONO (-3765 3685);
FORCEPROP 0 LASTPIN (-3775 4125) $PN 25
J 0
(-3765 4135);
DISPLAY 0.489362 (-3765 4135);
PAINT MONO (-3765 4135);
FORCEPROP 0 LASTPIN (-3775 4575) $PN 24
J 0
(-3765 4585);
DISPLAY 0.489362 (-3765 4585);
PAINT MONO (-3765 4585);
FORCEPROP 0 LASTPIN (-3775 5025) $PN 23
J 0
(-3765 5035);
DISPLAY 0.489362 (-3765 5035);
PAINT MONO (-3765 5035);
FORCEPROP 0 LASTPIN (-5125 5975) $PN 13
J 2
(-5135 5985);
DISPLAY 0.489362 (-5135 5985);
PAINT MONO (-5135 5985);
FORCEPROP 0 LASTPIN (-5125 1425) $PN 34
J 2
(-5135 1435);
DISPLAY 0.489362 (-5135 1435);
PAINT MONO (-5135 1435);
FORCEPROP 0 LASTPIN (-5125 4675) $PN 11
J 2
(-5135 4685);
DISPLAY 0.489362 (-5135 4685);
PAINT MONO (-5135 4685);
FORCEPROP 0 LASTPIN (-5125 2125) $PN 33
J 2
(-5135 2135);
DISPLAY 0.489362 (-5135 2135);
PAINT MONO (-5135 2135);
FORCEPROP 0 LASTPIN (-5125 6125) $PN 12
J 2
(-5135 6135);
DISPLAY 0.489362 (-5135 6135);
PAINT MONO (-5135 6135);
FORCEPROP 0 LASTPIN (-5125 875) $PN 16
J 2
(-5135 885);
DISPLAY 0.489362 (-5135 885);
PAINT MONO (-5135 885);
FORCEPROP 0 LASTPIN (-5125 4975) $PN 10
J 2
(-5135 4985);
DISPLAY 0.489362 (-5135 4985);
PAINT MONO (-5135 4985);
FORCEPROP 0 LASTPIN (-5125 4825) $PN 9
J 2
(-5135 4835);
DISPLAY 0.489362 (-5135 4835);
PAINT MONO (-5135 4835);
FORCEPROP 0 LASTPIN (-3775 1975) $PN 1
J 0
(-3765 1985);
DISPLAY 0.489362 (-3765 1985);
PAINT MONO (-3765 1985);
FORCEPROP 0 LASTPIN (-3775 2425) $PN 2
J 0
(-3765 2435);
DISPLAY 0.489362 (-3765 2435);
PAINT MONO (-3765 2435);
FORCEPROP 0 LASTPIN (-3775 2875) $PN 3
J 0
(-3765 2885);
DISPLAY 0.489362 (-3765 2885);
PAINT MONO (-3765 2885);
FORCEPROP 0 LASTPIN (-3775 3325) $PN 4
J 0
(-3765 3335);
DISPLAY 0.489362 (-3765 3335);
PAINT MONO (-3765 3335);
FORCEPROP 0 LASTPIN (-3775 3775) $PN 5
J 0
(-3765 3785);
DISPLAY 0.489362 (-3765 3785);
PAINT MONO (-3765 3785);
FORCEPROP 0 LASTPIN (-3775 4225) $PN 6
J 0
(-3765 4235);
DISPLAY 0.489362 (-3765 4235);
PAINT MONO (-3765 4235);
FORCEPROP 0 LASTPIN (-3775 4675) $PN 7
J 0
(-3765 4685);
DISPLAY 0.489362 (-3765 4685);
PAINT MONO (-3765 4685);
FORCEPROP 0 LASTPIN (-3775 5125) $PN 8
J 0
(-3765 5135);
DISPLAY 0.489362 (-3765 5135);
PAINT MONO (-3765 5135);
FORCEPROP 0 LASTPIN (-3775 1625) $PN 14
J 0
(-3765 1635);
DISPLAY 0.489362 (-3765 1635);
PAINT MONO (-3765 1635);
FORCEPROP 0 LASTPIN (-5125 3825) $PN 22
J 2
(-5135 3835);
DISPLAY 0.489362 (-5135 3835);
PAINT MONO (-5135 3835);
FORCEPROP 0 LASTPIN (-5125 2725) $PN 31
J 2
(-5135 2735);
DISPLAY 0.489362 (-5135 2735);
PAINT MONO (-5135 2735);
FORCEPROP 0 LASTPIN (-5125 5675) $PN 18
J 2
(-5135 5685);
DISPLAY 0.489362 (-5135 5685);
PAINT MONO (-5135 5685);
FORCEPROP 0 LASTPIN (-5125 5525) $PN 17
J 2
(-5135 5535);
DISPLAY 0.489362 (-5135 5535);
PAINT MONO (-5135 5535);
FORCEPROP 0 LASTPIN (-5125 5225) $PN 20
J 2
(-5135 5235);
DISPLAY 0.489362 (-5135 5235);
PAINT MONO (-5135 5235);
FORCEPROP 0 LASTPIN (-5125 5375) $PN 19
J 2
(-5135 5385);
DISPLAY 0.489362 (-5135 5385);
PAINT MONO (-5135 5385);
FORCEPROP 0 LASTPIN (-3775 925) $PN 36
J 0
(-3765 935);
DISPLAY 0.489362 (-3765 935);
PAINT MONO (-3765 935);
FORCEPROP 0 LASTPIN (-3775 1225) $PN 35
J 0
(-3765 1235);
DISPLAY 0.489362 (-3765 1235);
PAINT MONO (-3765 1235);
FORCEPROP 0 LASTPIN (-5125 575) $PN TH
J 2
(-5135 585);
DISPLAY 0.489362 (-5135 585);
PAINT MONO (-5135 585);
FORCEPROP 0 LASTPIN (-3775 6125) $PN 39
J 0
(-3765 6135);
DISPLAY 0.489362 (-3765 6135);
PAINT MONO (-3765 6135);
FORCEPROP 0 LASTPIN (-3775 5825) $PN 40
J 0
(-3765 5835);
DISPLAY 0.489362 (-3765 5835);
PAINT MONO (-3765 5835);
FORCEPROP 0 LASTPIN (-5125 1875) $PN 15
J 2
(-5135 1885);
DISPLAY 0.489362 (-5135 1885);
PAINT MONO (-5135 1885);
FORCEPROP 0 LASTPIN (-5125 675) $PN 38
J 2
(-5135 685);
DISPLAY 0.489362 (-5135 685);
PAINT MONO (-5135 685);
FORCEPROP 0 LASTPIN (-5125 775) $PN 37
J 2
(-5135 785);
DISPLAY 0.489362 (-5135 785);
PAINT MONO (-5135 785);
FORCEPROP 0 LASTPIN (-5125 4075) $PN 21
J 2
(-5135 4085);
DISPLAY 0.489362 (-5135 4085);
PAINT MONO (-5135 4085);
FORCEPROP 0 LASTPIN (-5125 2975) $PN 32
J 2
(-5135 2985);
DISPLAY 0.489362 (-5135 2985);
PAINT MONO (-5135 2985);
FORCEPROP 2 LAST PART_TYPE SMLF
J 0
(-4975 6525);
DISPLAY 1.021277 (-4975 6525);
FORCEPROP 2 LAST VALUE RAA229621GNP#HA0
J 0
(-4975 6475);
DISPLAY 0.489362 (-4975 6475);
PAINT SKYBLUE (-4975 6475);
FORCEPROP 1 LAST MATERIAL IC
J 0
(-4975 6250);
DISPLAY 0.489362 (-4975 6250);
PAINT SKYBLUE (-4975 6250);
FORCEPROP 2 LAST CDS_LIB pure_quanta
J 0
(-4425 3375);
DISPLAY INVISIBLE (-4425 3375);
FORCEPROP 1 LAST NEEDS_NO_SIZE TRUE
J 0
(-4425 3375);
DISPLAY 0.723404 (-4425 3375);
PAINT GREEN (-4425 3375);
DISPLAY INVISIBLE (-4425 3375);
FORCEPROP 1 LAST CDS_LMAN_SYM_OUTLINE -550,2850,500,-2850
J 0
(-4425 3375);
DISPLAY 0.468085 (-4425 3375);
PAINT GREEN (-4425 3375);
DISPLAY INVISIBLE (-4425 3375);
FORCEPROP 1 LAST PATH I24
J 0
(-4425 3375);
DISPLAY 0.723404 (-4425 3375);
PAINT GREEN (-4425 3375);
DISPLAY INVISIBLE (-4425 3375);
FORCEPROP 1 LAST PART_NUMBER ARF0TGP4003
J 0
(-4975 6325);
DISPLAY 0.489362 (-4975 6325);
PAINT SKYBLUE (-4975 6325);
DISPLAY INVISIBLE (-4975 6325);
FORCEADD Q_RES..2
(-6000 2350);
FORCEPROP 1 LAST LOCATION R124
J 0
(-5955 2475);
DISPLAY 0.489362 (-5955 2475);
PAINT SKYBLUE (-5955 2475);
FORCEPROP 0 LAST $SEC 1
J 0
(-5950 2525);
DISPLAY 0.680851 (-5950 2525);
PAINT MONO (-5950 2525);
DISPLAY INVISIBLE (-5950 2525);
FORCEPROP 0 LAST CDS_SEC 1
J 0
(-5950 2525);
DISPLAY 1.021277 (-5950 2525);
DISPLAY INVISIBLE (-5950 2525);
FORCEPROP 1 LASTPIN (-6000 2450) $PN 1
J 0
(-5995 2412);
DISPLAY 0.489362 (-5995 2412);
PAINT MONO (-5995 2412);
FORCEPROP 1 LASTPIN (-6000 2250) $PN 2
J 0
(-5995 2260);
DISPLAY 0.489362 (-5995 2260);
PAINT MONO (-5995 2260);
FORCEPROP 1 LAST TOLERANCE 1%
J 0
(-5955 2375);
DISPLAY 0.489362 (-5955 2375);
PAINT SKYBLUE (-5955 2375);
FORCEPROP 1 LAST VALUE 1K
J 0
(-5955 2425);
DISPLAY 0.489362 (-5955 2425);
PAINT SKYBLUE (-5955 2425);
FORCEPROP 1 LAST MATERIAL EMPTY
J 0
(-5960 2275);
DISPLAY 0.489362 (-5960 2275);
PAINT RED (-5960 2275);
FORCEPROP 1 LAST PACK_TYPE 0402LF
J 0
(-5960 2175);
DISPLAY 0.489362 (-5960 2175);
PAINT SKYBLUE (-5960 2175);
FORCEPROP 1 LAST WATTAGE 1/16W
J 0
(-5960 2325);
DISPLAY 0.489362 (-5960 2325);
PAINT SKYBLUE (-5960 2325);
FORCEPROP 2 LAST CDS_LIB pure_quanta
J 0
(-6000 2350);
DISPLAY INVISIBLE (-6000 2350);
FORCEPROP 1 LAST PATH I25
J 0
(-5950 2525);
DISPLAY 0.978723 (-5950 2525);
PAINT WHITE (-5950 2525);
DISPLAY INVISIBLE (-5950 2525);
FORCEPROP 1 LAST PART_NUMBER CS21002FB06
J 0
(-5960 2225);
DISPLAY 0.489362 (-5960 2225);
PAINT SKYBLUE (-5960 2225);
DISPLAY INVISIBLE (-5960 2225);
FORCEADD VCC_CORE..1
(-6000 2550);
FORCEPROP 3 LASTPIN (-6000 2500) SIG_NAME PVDD18_S5_P0\g
J 0
(-5990 2510);
DISPLAY 0.659574 (-5990 2510);
PAINT MONO (-5990 2510);
DISPLAY INVISIBLE (-5990 2510);
FORCEPROP 1 LAST HDL_POWER PVDD18_S5_P0
J 1
(-6000 2600);
DISPLAY 0.489362 (-6000 2600);
PAINT GREEN (-6000 2600);
FORCEPROP 2 LAST CDS_LIB pure_quanta_power
J 0
(-6000 2550);
DISPLAY INVISIBLE (-6000 2550);
FORCEPROP 1 LAST PATH I26
J 0
(-5950 2575);
DISPLAY 0.872340 (-5950 2575);
PAINT AQUA (-5950 2575);
DISPLAY INVISIBLE (-5950 2575);
FORCEADD UNIVERSAL_GND..1
R 2
(-5400 2575);
FORCEPROP 3 LASTPIN (-5400 2625) SIG_NAME GND\g
J 0
(-5390 2635);
DISPLAY 0.659574 (-5390 2635);
PAINT MONO (-5390 2635);
DISPLAY INVISIBLE (-5390 2635);
FORCEPROP 2 LAST CDS_LIB pure_quanta_power
J 0
(-5400 2575);
DISPLAY INVISIBLE (-5400 2575);
FORCEPROP 1 LAST HDL_POWER GND
J 1
(-5425 2500);
DISPLAY 0.872340 (-5425 2500);
PAINT GREEN (-5425 2500);
DISPLAY INVISIBLE (-5425 2500);
FORCEPROP 1 LAST PATH I27
J 2
(-5475 2575);
DISPLAY 0.872340 (-5475 2575);
PAINT AQUA (-5475 2575);
DISPLAY INVISIBLE (-5475 2575);
FORCEADD Q_RES..1
(-6075 4075);
FORCEPROP 1 LAST LOCATION PR121
J 0
(-6125 4125);
DISPLAY 0.489362 (-6125 4125);
PAINT SKYBLUE (-6125 4125);
FORCEPROP 0 LAST $SEC 1
J 0
(-6125 4150);
DISPLAY 0.680851 (-6125 4150);
PAINT MONO (-6125 4150);
DISPLAY INVISIBLE (-6125 4150);
FORCEPROP 0 LAST CDS_SEC 1
J 0
(-6125 4150);
DISPLAY 1.021277 (-6125 4150);
DISPLAY INVISIBLE (-6125 4150);
FORCEPROP 1 LASTPIN (-6175 4075) $PN 1
J 0
(-6163 4087);
DISPLAY 0.489362 (-6163 4087);
PAINT MONO (-6163 4087);
FORCEPROP 1 LASTPIN (-5975 4075) $PN 2
J 0
(-6013 4087);
DISPLAY 0.489362 (-6013 4087);
PAINT MONO (-6013 4087);
FORCEPROP 1 LAST TOLERANCE 5%
J 0
(-5950 4100);
DISPLAY 0.489362 (-5950 4100);
PAINT SKYBLUE (-5950 4100);
FORCEPROP 1 LAST WATTAGE 1/16W
J 0
(-5975 4025);
DISPLAY 0.489362 (-5975 4025);
PAINT SKYBLUE (-5975 4025);
FORCEPROP 1 LAST PACK_TYPE 0402LF
J 0
(-5975 4000);
DISPLAY 0.489362 (-5975 4000);
PAINT SKYBLUE (-5975 4000);
FORCEPROP 1 LAST VALUE 0
J 2
(-6200 4100);
DISPLAY 0.489362 (-6200 4100);
PAINT SKYBLUE (-6200 4100);
FORCEPROP 1 LAST MATERIAL CHIP
J 0
(-6400 4000);
DISPLAY 0.489362 (-6400 4000);
PAINT SKYBLUE (-6400 4000);
FORCEPROP 2 LAST CDS_LIB pure_quanta
J 0
(-6075 4075);
DISPLAY INVISIBLE (-6075 4075);
FORCEPROP 1 LAST PATH I28
J 0
(-6125 4225);
DISPLAY 0.978723 (-6125 4225);
PAINT WHITE (-6125 4225);
DISPLAY INVISIBLE (-6125 4225);
FORCEPROP 1 LAST PART_NUMBER CS00002JB13
J 0
(-6400 4025);
DISPLAY 0.489362 (-6400 4025);
PAINT SKYBLUE (-6400 4025);
DISPLAY INVISIBLE (-6400 4025);
FORCEADD Q_CAP..1
(-5775 3950);
FORCEPROP 1 LAST LOCATION PC194
J 0
(-5725 4000);
DISPLAY 0.489362 (-5725 4000);
PAINT SKYBLUE (-5725 4000);
FORCEPROP 0 LAST $SEC 1
J 0
(-5725 4025);
DISPLAY 0.680851 (-5725 4025);
PAINT MONO (-5725 4025);
DISPLAY INVISIBLE (-5725 4025);
FORCEPROP 0 LAST CDS_SEC 1
J 0
(-5725 4025);
DISPLAY 1.021277 (-5725 4025);
DISPLAY INVISIBLE (-5725 4025);
FORCEPROP 1 LASTPIN (-5775 4050) $PN 1
J 0
(-5765 4030);
DISPLAY 0.489362 (-5765 4030);
PAINT MONO (-5765 4030);
FORCEPROP 1 LASTPIN (-5775 3850) $PN 2
J 0
(-5765 3830);
DISPLAY 0.489362 (-5765 3830);
PAINT MONO (-5765 3830);
FORCEPROP 1 LAST MATERIAL X7R
J 0
(-5725 3900);
DISPLAY 0.489362 (-5725 3900);
PAINT SKYBLUE (-5725 3900);
FORCEPROP 1 LAST TOLERANCE 10%
J 0
(-5725 3925);
DISPLAY 0.489362 (-5725 3925);
PAINT SKYBLUE (-5725 3925);
FORCEPROP 1 LAST VOLTAGE 50V
J 0
(-5725 3950);
DISPLAY 0.489362 (-5725 3950);
PAINT SKYBLUE (-5725 3950);
FORCEPROP 1 LAST PACK_TYPE 0402
J 0
(-5725 3850);
DISPLAY 0.489362 (-5725 3850);
PAINT SKYBLUE (-5725 3850);
FORCEPROP 1 LAST VALUE 3300PF
J 0
(-5725 3975);
DISPLAY 0.489362 (-5725 3975);
PAINT SKYBLUE (-5725 3975);
FORCEPROP 2 LAST CDS_LIB pure_quanta
J 0
(-5775 3950);
DISPLAY INVISIBLE (-5775 3950);
FORCEPROP 1 LAST PATH I29
J 0
(-5725 4100);
DISPLAY 0.978723 (-5725 4100);
PAINT WHITE (-5725 4100);
DISPLAY INVISIBLE (-5725 4100);
FORCEPROP 1 LAST PART_NUMBER TMP_QCH2336K1B12
J 0
(-5725 3875);
DISPLAY 0.489362 (-5725 3875);
PAINT SKYBLUE (-5725 3875);
DISPLAY INVISIBLE (-5725 3875);
FORCEADD UNIVERSAL_GND..1
(-6975 400);
FORCEPROP 3 LASTPIN (-6975 450) SIG_NAME GND\g
J 0
(-6965 460);
DISPLAY 0.659574 (-6965 460);
PAINT MONO (-6965 460);
DISPLAY INVISIBLE (-6965 460);
FORCEPROP 2 LAST CDS_LIB pure_quanta_power
J 0
(-6975 400);
DISPLAY INVISIBLE (-6975 400);
FORCEPROP 1 LAST HDL_POWER GND
J 1
(-6950 325);
DISPLAY 0.872340 (-6950 325);
PAINT GREEN (-6950 325);
DISPLAY INVISIBLE (-6950 325);
FORCEPROP 1 LAST PATH I3
J 0
(-6900 400);
DISPLAY 0.872340 (-6900 400);
PAINT AQUA (-6900 400);
DISPLAY INVISIBLE (-6900 400);
FORCEADD Q_RES..2
(-6900 4250);
FORCEPROP 1 LAST LOCATION PR114
J 0
(-6850 4375);
DISPLAY 0.489362 (-6850 4375);
PAINT SKYBLUE (-6850 4375);
FORCEPROP 0 LAST $SEC 1
J 0
(-6850 4400);
DISPLAY 0.680851 (-6850 4400);
PAINT MONO (-6850 4400);
DISPLAY INVISIBLE (-6850 4400);
FORCEPROP 0 LAST CDS_SEC 1
J 0
(-6850 4400);
DISPLAY 1.021277 (-6850 4400);
DISPLAY INVISIBLE (-6850 4400);
FORCEPROP 1 LASTPIN (-6900 4350) $PN 1
J 0
(-6895 4312);
DISPLAY 0.489362 (-6895 4312);
PAINT MONO (-6895 4312);
FORCEPROP 1 LASTPIN (-6900 4150) $PN 2
J 0
(-6895 4160);
DISPLAY 0.489362 (-6895 4160);
PAINT MONO (-6895 4160);
FORCEPROP 1 LAST WATTAGE 1/16W
J 0
(-6850 4225);
DISPLAY 0.489362 (-6850 4225);
PAINT SKYBLUE (-6850 4225);
FORCEPROP 1 LAST VALUE 49.9
J 0
(-6850 4325);
DISPLAY 0.489362 (-6850 4325);
PAINT SKYBLUE (-6850 4325);
FORCEPROP 1 LAST MATERIAL CHIP
J 0
(-6850 4175);
DISPLAY 0.489362 (-6850 4175);
PAINT SKYBLUE (-6850 4175);
FORCEPROP 1 LAST PACK_TYPE 0402LF
J 0
(-6850 4075);
DISPLAY 0.489362 (-6850 4075);
PAINT SKYBLUE (-6850 4075);
FORCEPROP 1 LAST TOLERANCE 1%
J 0
(-6850 4275);
DISPLAY 0.489362 (-6850 4275);
PAINT SKYBLUE (-6850 4275);
FORCEPROP 2 LAST CDS_LIB pure_quanta
J 0
(-6900 4250);
DISPLAY INVISIBLE (-6900 4250);
FORCEPROP 1 LAST PATH I30
J 0
(-6850 4425);
DISPLAY 0.978723 (-6850 4425);
PAINT WHITE (-6850 4425);
DISPLAY INVISIBLE (-6850 4425);
FORCEPROP 1 LAST PART_NUMBER CS04992FB07
J 0
(-6850 4125);
DISPLAY 0.489362 (-6850 4125);
PAINT SKYBLUE (-6850 4125);
DISPLAY INVISIBLE (-6850 4125);
FORCEADD VCC_CORE..1
(-6900 4450);
FORCEPROP 3 LASTPIN (-6900 4400) SIG_NAME PVDD11_S3_P0\g
J 0
(-6890 4410);
DISPLAY 0.659574 (-6890 4410);
PAINT MONO (-6890 4410);
DISPLAY INVISIBLE (-6890 4410);
FORCEPROP 1 LAST HDL_POWER PVDD11_S3_P0
J 1
(-6900 4500);
DISPLAY 0.489362 (-6900 4500);
PAINT GREEN (-6900 4500);
FORCEPROP 2 LAST CDS_LIB pure_quanta_power
J 0
(-6900 4450);
DISPLAY INVISIBLE (-6900 4450);
FORCEPROP 1 LAST PATH I31
J 0
(-6850 4475);
DISPLAY 0.872340 (-6850 4475);
PAINT AQUA (-6850 4475);
DISPLAY INVISIBLE (-6850 4475);
FORCEADD OFFPAGE..2
R 2
(-6850 4675);
FORCEPROP 2 LAST $XR0 83 
J 0
(-7104 4675);
DISPLAY 0.638298 (-7104 4675);
PAINT MONO (-7104 4675);
FORCEPROP 2 LAST $XR1 82 
J 0
(-7194 4675);
DISPLAY 0.638298 (-7194 4675);
PAINT MONO (-7194 4675);
FORCEPROP 2 LAST CDS_LIB standard
J 0
(-6850 4675);
DISPLAY INVISIBLE (-6850 4675);
FORCEPROP 1 LAST OFFPAGE TRUE
J 2
(-7175 4550);
DISPLAY 0.872340 (-7175 4550);
PAINT GREEN (-7175 4550);
DISPLAY INVISIBLE (-7175 4550);
FORCEPROP 1 LAST COMMENT_BODY TRUE
J 2
(-6805 4580);
DISPLAY 0.872340 (-6805 4580);
PAINT GREEN (-6805 4580);
DISPLAY INVISIBLE (-6805 4580);
FORCEPROP 2 LAST PATH I32
J 0
(-7050 4725);
DISPLAY 0.680851 (-7050 4725);
DISPLAY INVISIBLE (-7050 4725);
FORCEADD OFFPAGE..2
R 2
(-6850 4825);
FORCEPROP 2 LAST $XR0 151 
J 0
(-7135 4825);
DISPLAY 0.638298 (-7135 4825);
PAINT MONO (-7135 4825);
FORCEPROP 2 LAST CDS_LIB standard
J 0
(-6850 4825);
DISPLAY INVISIBLE (-6850 4825);
FORCEPROP 1 LAST OFFPAGE TRUE
J 2
(-7175 4700);
DISPLAY 0.872340 (-7175 4700);
PAINT GREEN (-7175 4700);
DISPLAY INVISIBLE (-7175 4700);
FORCEPROP 1 LAST COMMENT_BODY TRUE
J 2
(-6805 4730);
DISPLAY 0.872340 (-6805 4730);
PAINT GREEN (-6805 4730);
DISPLAY INVISIBLE (-6805 4730);
FORCEPROP 2 LAST PATH I33
J 0
(-7100 4875);
DISPLAY 0.680851 (-7100 4875);
DISPLAY INVISIBLE (-7100 4875);
FORCEADD OFFPAGE..2
R 2
(-6850 4975);
FORCEPROP 2 LAST $XR0 151 
J 0
(-7135 4975);
DISPLAY 0.638298 (-7135 4975);
PAINT MONO (-7135 4975);
FORCEPROP 2 LAST CDS_LIB standard
J 0
(-6850 4975);
DISPLAY INVISIBLE (-6850 4975);
FORCEPROP 1 LAST OFFPAGE TRUE
J 2
(-7175 4850);
DISPLAY 0.872340 (-7175 4850);
PAINT GREEN (-7175 4850);
DISPLAY INVISIBLE (-7175 4850);
FORCEPROP 1 LAST COMMENT_BODY TRUE
J 2
(-6805 4880);
DISPLAY 0.872340 (-6805 4880);
PAINT GREEN (-6805 4880);
DISPLAY INVISIBLE (-6805 4880);
FORCEPROP 2 LAST PATH I34
J 0
(-7100 5025);
DISPLAY 0.680851 (-7100 5025);
DISPLAY INVISIBLE (-7100 5025);
FORCEADD OFFPAGE..2
R 2
(-6725 6125);
FORCEPROP 2 LAST $XR0 81 
J 0
(-6979 6125);
DISPLAY 0.638298 (-6979 6125);
PAINT MONO (-6979 6125);
FORCEPROP 2 LAST CDS_LIB standard
J 0
(-6725 6125);
DISPLAY INVISIBLE (-6725 6125);
FORCEPROP 1 LAST OFFPAGE TRUE
J 2
(-7050 6000);
DISPLAY 0.872340 (-7050 6000);
PAINT GREEN (-7050 6000);
DISPLAY INVISIBLE (-7050 6000);
FORCEPROP 1 LAST COMMENT_BODY TRUE
J 2
(-6680 6030);
DISPLAY 0.872340 (-6680 6030);
PAINT GREEN (-6680 6030);
DISPLAY INVISIBLE (-6680 6030);
FORCEPROP 2 LAST PATH I35
J 0
(-6975 6175);
DISPLAY 0.680851 (-6975 6175);
DISPLAY INVISIBLE (-6975 6175);
FORCEADD OFFPAGE..4
R 4
(-6725 5975);
FORCEPROP 2 LAST $XR0 82 
J 0
(-6946 5975);
DISPLAY 0.638298 (-6946 5975);
PAINT MONO (-6946 5975);
FORCEPROP 2 LAST CDS_LIB standard
R 2
J 2
(-6725 5975);
DISPLAY INVISIBLE (-6725 5975);
FORCEPROP 1 LAST OFFPAGE TRUE
R 2
J 0
(-7050 6100);
DISPLAY 0.872340 (-7050 6100);
PAINT GREEN (-7050 6100);
DISPLAY INVISIBLE (-7050 6100);
FORCEPROP 1 LAST COMMENT_BODY TRUE
R 2
J 0
(-6700 6075);
DISPLAY 0.872340 (-6700 6075);
PAINT GREEN (-6700 6075);
DISPLAY INVISIBLE (-6700 6075);
FORCEPROP 2 LAST PATH I36
J 0
(-6925 6025);
DISPLAY 0.680851 (-6925 6025);
DISPLAY INVISIBLE (-6925 6025);
FORCEADD VCC_CORE..1
(-6625 6525);
FORCEPROP 3 LASTPIN (-6625 6475) SIG_NAME P3V3_AUX\g
J 0
(-6615 6485);
DISPLAY 0.659574 (-6615 6485);
PAINT MONO (-6615 6485);
DISPLAY INVISIBLE (-6615 6485);
FORCEPROP 1 LAST HDL_POWER P3V3_AUX
J 1
(-6625 6575);
DISPLAY 0.489362 (-6625 6575);
PAINT GREEN (-6625 6575);
FORCEPROP 2 LAST CDS_LIB pure_quanta_power
J 0
(-6625 6525);
DISPLAY INVISIBLE (-6625 6525);
FORCEPROP 1 LAST PATH I37
J 0
(-6575 6550);
DISPLAY 0.872340 (-6575 6550);
PAINT AQUA (-6575 6550);
DISPLAY INVISIBLE (-6575 6550);
FORCEADD Q_RES..1
(-6225 6400);
FORCEPROP 1 LAST LOCATION R117
J 0
(-6275 6450);
DISPLAY 0.489362 (-6275 6450);
PAINT SKYBLUE (-6275 6450);
FORCEPROP 0 LAST $SEC 1
J 0
(-6275 6500);
DISPLAY 0.680851 (-6275 6500);
PAINT MONO (-6275 6500);
DISPLAY INVISIBLE (-6275 6500);
FORCEPROP 0 LAST CDS_SEC 1
J 0
(-6275 6500);
DISPLAY 1.021277 (-6275 6500);
DISPLAY INVISIBLE (-6275 6500);
FORCEPROP 1 LASTPIN (-6325 6400) $PN 1
J 0
(-6313 6412);
DISPLAY 0.489362 (-6313 6412);
PAINT MONO (-6313 6412);
FORCEPROP 1 LASTPIN (-6125 6400) $PN 2
J 0
(-6163 6412);
DISPLAY 0.489362 (-6163 6412);
PAINT MONO (-6163 6412);
FORCEPROP 1 LAST MATERIAL CHIP
J 0
(-6550 6300);
DISPLAY 0.489362 (-6550 6300);
PAINT SKYBLUE (-6550 6300);
FORCEPROP 1 LAST VALUE 1K
J 2
(-6375 6425);
DISPLAY 0.489362 (-6375 6425);
PAINT SKYBLUE (-6375 6425);
FORCEPROP 1 LAST TOLERANCE 1%
J 0
(-6100 6425);
DISPLAY 0.489362 (-6100 6425);
PAINT SKYBLUE (-6100 6425);
FORCEPROP 1 LAST WATTAGE 1/16W
J 0
(-6125 6350);
DISPLAY 0.489362 (-6125 6350);
PAINT SKYBLUE (-6125 6350);
FORCEPROP 1 LAST PACK_TYPE 0402LF
J 0
(-6125 6300);
DISPLAY 0.489362 (-6125 6300);
PAINT SKYBLUE (-6125 6300);
FORCEPROP 2 LAST CDS_LIB pure_quanta
J 0
(-6225 6400);
DISPLAY INVISIBLE (-6225 6400);
FORCEPROP 1 LAST PATH I38
J 0
(-6275 6550);
DISPLAY 0.978723 (-6275 6550);
PAINT WHITE (-6275 6550);
DISPLAY INVISIBLE (-6275 6550);
FORCEPROP 1 LAST PART_NUMBER CS21002FB06
J 0
(-6550 6350);
DISPLAY 0.489362 (-6550 6350);
PAINT SKYBLUE (-6550 6350);
DISPLAY INVISIBLE (-6550 6350);
FORCEADD Q_RES..1
(-6075 4675);
FORCEPROP 1 LAST LOCATION R120
J 0
(-6125 4725);
DISPLAY 0.489362 (-6125 4725);
PAINT SKYBLUE (-6125 4725);
FORCEPROP 0 LAST $SEC 1
J 0
(-6125 4750);
DISPLAY 0.680851 (-6125 4750);
PAINT MONO (-6125 4750);
DISPLAY INVISIBLE (-6125 4750);
FORCEPROP 0 LAST CDS_SEC 1
J 0
(-6125 4750);
DISPLAY 1.021277 (-6125 4750);
DISPLAY INVISIBLE (-6125 4750);
FORCEPROP 1 LASTPIN (-6175 4675) $PN 1
J 0
(-6163 4687);
DISPLAY 0.489362 (-6163 4687);
PAINT MONO (-6163 4687);
FORCEPROP 1 LASTPIN (-5975 4675) $PN 2
J 0
(-6013 4687);
DISPLAY 0.489362 (-6013 4687);
PAINT MONO (-6013 4687);
FORCEPROP 1 LAST WATTAGE 1/16W
J 0
(-5975 4625);
DISPLAY 0.489362 (-5975 4625);
PAINT SKYBLUE (-5975 4625);
FORCEPROP 1 LAST VALUE 33
J 2
(-6200 4700);
DISPLAY 0.489362 (-6200 4700);
PAINT SKYBLUE (-6200 4700);
FORCEPROP 1 LAST MATERIAL CHIP
J 0
(-6325 4600);
DISPLAY 0.489362 (-6325 4600);
PAINT SKYBLUE (-6325 4600);
FORCEPROP 1 LAST PACK_TYPE 0402LF
J 0
(-5975 4600);
DISPLAY 0.489362 (-5975 4600);
PAINT SKYBLUE (-5975 4600);
FORCEPROP 1 LAST TOLERANCE 5%
J 0
(-5950 4700);
DISPLAY 0.489362 (-5950 4700);
PAINT SKYBLUE (-5950 4700);
FORCEPROP 2 LAST CDS_LIB pure_quanta
J 0
(-6075 4675);
DISPLAY INVISIBLE (-6075 4675);
FORCEPROP 1 LAST PATH I39
J 0
(-6125 4825);
DISPLAY 0.978723 (-6125 4825);
PAINT WHITE (-6125 4825);
DISPLAY INVISIBLE (-6125 4825);
FORCEPROP 1 LAST PART_NUMBER CS03302JB10
J 0
(-6325 4625);
DISPLAY 0.489362 (-6325 4625);
PAINT SKYBLUE (-6325 4625);
DISPLAY INVISIBLE (-6325 4625);
FORCEADD Q_CAP..1
(-6975 675);
FORCEPROP 1 LAST LOCATION PC193
J 0
(-6900 775);
DISPLAY 0.489362 (-6900 775);
PAINT SKYBLUE (-6900 775);
FORCEPROP 0 LAST $SEC 1
J 0
(-6925 800);
DISPLAY 0.680851 (-6925 800);
PAINT MONO (-6925 800);
DISPLAY INVISIBLE (-6925 800);
FORCEPROP 0 LAST CDS_SEC 1
J 0
(-6925 800);
DISPLAY 1.021277 (-6925 800);
DISPLAY INVISIBLE (-6925 800);
FORCEPROP 1 LASTPIN (-6975 775) $PN 1
J 0
(-6965 755);
DISPLAY 0.489362 (-6965 755);
PAINT MONO (-6965 755);
FORCEPROP 1 LASTPIN (-6975 575) $PN 2
J 0
(-6965 555);
DISPLAY 0.489362 (-6965 555);
PAINT MONO (-6965 555);
FORCEPROP 1 LAST VOLTAGE 25V
J 0
(-6900 675);
DISPLAY 0.489362 (-6900 675);
PAINT SKYBLUE (-6900 675);
FORCEPROP 1 LAST TOLERANCE 10%
J 0
(-6900 625);
DISPLAY 0.489362 (-6900 625);
PAINT SKYBLUE (-6900 625);
FORCEPROP 1 LAST MATERIAL X7R
J 0
(-6900 575);
DISPLAY 0.489362 (-6900 575);
PAINT SKYBLUE (-6900 575);
FORCEPROP 1 LAST PACK_TYPE 0402
J 0
(-6900 475);
DISPLAY 0.489362 (-6900 475);
PAINT SKYBLUE (-6900 475);
FORCEPROP 1 LAST VALUE 0.1UF
J 0
(-6900 725);
DISPLAY 0.489362 (-6900 725);
PAINT SKYBLUE (-6900 725);
FORCEPROP 2 LAST CDS_LIB pure_quanta
J 0
(-6975 675);
DISPLAY INVISIBLE (-6975 675);
FORCEPROP 1 LAST PATH I4
J 0
(-6925 825);
DISPLAY 0.978723 (-6925 825);
PAINT WHITE (-6925 825);
DISPLAY INVISIBLE (-6925 825);
FORCEPROP 1 LAST PART_NUMBER CH4104K1B00
J 0
(-6900 525);
DISPLAY 0.489362 (-6900 525);
PAINT SKYBLUE (-6900 525);
DISPLAY INVISIBLE (-6900 525);
FORCEADD Q_RES..1
(-6075 4825);
FORCEPROP 1 LAST LOCATION R119
J 0
(-6125 4875);
DISPLAY 0.489362 (-6125 4875);
PAINT SKYBLUE (-6125 4875);
FORCEPROP 0 LAST $SEC 1
J 0
(-6125 4900);
DISPLAY 0.680851 (-6125 4900);
PAINT MONO (-6125 4900);
DISPLAY INVISIBLE (-6125 4900);
FORCEPROP 0 LAST CDS_SEC 1
J 0
(-6125 4900);
DISPLAY 1.021277 (-6125 4900);
DISPLAY INVISIBLE (-6125 4900);
FORCEPROP 1 LASTPIN (-6175 4825) $PN 1
J 0
(-6163 4837);
DISPLAY 0.489362 (-6163 4837);
PAINT MONO (-6163 4837);
FORCEPROP 1 LASTPIN (-5975 4825) $PN 2
J 0
(-6013 4837);
DISPLAY 0.489362 (-6013 4837);
PAINT MONO (-6013 4837);
FORCEPROP 1 LAST TOLERANCE 5%
J 0
(-5950 4850);
DISPLAY 0.489362 (-5950 4850);
PAINT SKYBLUE (-5950 4850);
FORCEPROP 1 LAST VALUE 0
J 2
(-6200 4850);
DISPLAY 0.489362 (-6200 4850);
PAINT SKYBLUE (-6200 4850);
FORCEPROP 1 LAST MATERIAL CHIP
J 0
(-6325 4750);
DISPLAY 0.489362 (-6325 4750);
PAINT SKYBLUE (-6325 4750);
FORCEPROP 1 LAST PACK_TYPE 0402LF
J 0
(-5975 4750);
DISPLAY 0.489362 (-5975 4750);
PAINT SKYBLUE (-5975 4750);
FORCEPROP 1 LAST WATTAGE 1/16W
J 0
(-5975 4775);
DISPLAY 0.489362 (-5975 4775);
PAINT SKYBLUE (-5975 4775);
FORCEPROP 2 LAST CDS_LIB pure_quanta
J 0
(-6075 4825);
DISPLAY INVISIBLE (-6075 4825);
FORCEPROP 1 LAST PATH I40
J 0
(-6125 4975);
DISPLAY 0.978723 (-6125 4975);
PAINT WHITE (-6125 4975);
DISPLAY INVISIBLE (-6125 4975);
FORCEPROP 1 LAST PART_NUMBER CS00002JB13
J 0
(-6325 4775);
DISPLAY 0.489362 (-6325 4775);
PAINT SKYBLUE (-6325 4775);
DISPLAY INVISIBLE (-6325 4775);
FORCEADD Q_RES..1
(-6075 4975);
FORCEPROP 1 LAST LOCATION R118
J 0
(-6125 5025);
DISPLAY 0.489362 (-6125 5025);
PAINT SKYBLUE (-6125 5025);
FORCEPROP 0 LAST $SEC 1
J 0
(-6125 5050);
DISPLAY 0.680851 (-6125 5050);
PAINT MONO (-6125 5050);
DISPLAY INVISIBLE (-6125 5050);
FORCEPROP 0 LAST CDS_SEC 1
J 0
(-6125 5050);
DISPLAY 1.021277 (-6125 5050);
DISPLAY INVISIBLE (-6125 5050);
FORCEPROP 1 LASTPIN (-6175 4975) $PN 1
J 0
(-6163 4987);
DISPLAY 0.489362 (-6163 4987);
PAINT MONO (-6163 4987);
FORCEPROP 1 LASTPIN (-5975 4975) $PN 2
J 0
(-6013 4987);
DISPLAY 0.489362 (-6013 4987);
PAINT MONO (-6013 4987);
FORCEPROP 1 LAST MATERIAL CHIP
J 0
(-6325 4900);
DISPLAY 0.489362 (-6325 4900);
PAINT SKYBLUE (-6325 4900);
FORCEPROP 1 LAST PACK_TYPE 0402LF
J 0
(-5975 4900);
DISPLAY 0.489362 (-5975 4900);
PAINT SKYBLUE (-5975 4900);
FORCEPROP 1 LAST WATTAGE 1/16W
J 0
(-5975 4925);
DISPLAY 0.489362 (-5975 4925);
PAINT SKYBLUE (-5975 4925);
FORCEPROP 1 LAST TOLERANCE 5%
J 0
(-5950 5000);
DISPLAY 0.489362 (-5950 5000);
PAINT SKYBLUE (-5950 5000);
FORCEPROP 1 LAST VALUE 0
J 2
(-6200 5000);
DISPLAY 0.489362 (-6200 5000);
PAINT SKYBLUE (-6200 5000);
FORCEPROP 2 LAST CDS_LIB pure_quanta
J 0
(-6075 4975);
DISPLAY INVISIBLE (-6075 4975);
FORCEPROP 1 LAST PATH I41
J 0
(-6125 5125);
DISPLAY 0.978723 (-6125 5125);
PAINT WHITE (-6125 5125);
DISPLAY INVISIBLE (-6125 5125);
FORCEPROP 1 LAST PART_NUMBER CS00002JB13
J 0
(-6325 4925);
DISPLAY 0.489362 (-6325 4925);
PAINT SKYBLUE (-6325 4925);
DISPLAY INVISIBLE (-6325 4925);
FORCEADD UNIVERSAL_GND..1
(-6075 5125);
FORCEPROP 3 LASTPIN (-6075 5175) SIG_NAME GND\g
J 0
(-6065 5185);
DISPLAY 0.659574 (-6065 5185);
PAINT MONO (-6065 5185);
DISPLAY INVISIBLE (-6065 5185);
FORCEPROP 2 LAST CDS_LIB pure_quanta_power
J 0
(-6075 5125);
DISPLAY INVISIBLE (-6075 5125);
FORCEPROP 1 LAST HDL_POWER GND
J 1
(-6050 5050);
DISPLAY 0.872340 (-6050 5050);
PAINT GREEN (-6050 5050);
DISPLAY INVISIBLE (-6050 5050);
FORCEPROP 1 LAST PATH I42
J 0
(-6000 5125);
DISPLAY 0.872340 (-6000 5125);
PAINT AQUA (-6000 5125);
DISPLAY INVISIBLE (-6000 5125);
FORCEADD Q_RES..1
(-6000 5975);
FORCEPROP 1 LAST LOCATION R123
J 0
(-6050 6000);
DISPLAY 0.489362 (-6050 6000);
PAINT SKYBLUE (-6050 6000);
FORCEPROP 0 LAST $SEC 1
J 0
(-5875 6025);
DISPLAY 0.680851 (-5875 6025);
PAINT MONO (-5875 6025);
DISPLAY INVISIBLE (-5875 6025);
FORCEPROP 0 LAST CDS_SEC 1
J 0
(-5875 6025);
DISPLAY 1.021277 (-5875 6025);
DISPLAY INVISIBLE (-5875 6025);
FORCEPROP 1 LASTPIN (-6100 5975) $PN 1
J 0
(-6088 5987);
DISPLAY 0.489362 (-6088 5987);
PAINT MONO (-6088 5987);
FORCEPROP 1 LASTPIN (-5900 5975) $PN 2
J 0
(-5938 5987);
DISPLAY 0.489362 (-5938 5987);
PAINT MONO (-5938 5987);
FORCEPROP 1 LAST PACK_TYPE 0402LF
J 0
(-5900 5900);
DISPLAY 0.489362 (-5900 5900);
PAINT SKYBLUE (-5900 5900);
FORCEPROP 1 LAST VALUE 0
J 2
(-6125 6000);
DISPLAY 0.489362 (-6125 6000);
PAINT SKYBLUE (-6125 6000);
FORCEPROP 1 LAST MATERIAL CHIP
J 0
(-6250 5900);
DISPLAY 0.489362 (-6250 5900);
PAINT SKYBLUE (-6250 5900);
FORCEPROP 1 LAST TOLERANCE 5%
J 0
(-5875 6000);
DISPLAY 0.489362 (-5875 6000);
PAINT SKYBLUE (-5875 6000);
FORCEPROP 1 LAST WATTAGE 1/16W
J 0
(-5900 5925);
DISPLAY 0.489362 (-5900 5925);
PAINT SKYBLUE (-5900 5925);
FORCEPROP 2 LAST CDS_LIB pure_quanta
J 0
(-6000 5975);
DISPLAY INVISIBLE (-6000 5975);
FORCEPROP 1 LAST PATH I43
J 0
(-6050 6125);
DISPLAY 0.978723 (-6050 6125);
PAINT WHITE (-6050 6125);
DISPLAY INVISIBLE (-6050 6125);
FORCEPROP 1 LAST PART_NUMBER CS00002JB13
J 0
(-6250 5925);
DISPLAY 0.489362 (-6250 5925);
PAINT SKYBLUE (-6250 5925);
DISPLAY INVISIBLE (-6250 5925);
FORCEADD Q_RES..1
(-6000 6125);
FORCEPROP 1 LAST LOCATION R122
J 0
(-6050 6175);
DISPLAY 0.489362 (-6050 6175);
PAINT SKYBLUE (-6050 6175);
FORCEPROP 0 LAST $SEC 1
J 0
(-6050 6225);
DISPLAY 0.680851 (-6050 6225);
PAINT MONO (-6050 6225);
DISPLAY INVISIBLE (-6050 6225);
FORCEPROP 0 LAST CDS_SEC 1
J 0
(-6050 6225);
DISPLAY 1.021277 (-6050 6225);
DISPLAY INVISIBLE (-6050 6225);
FORCEPROP 1 LASTPIN (-6100 6125) $PN 1
J 0
(-6088 6137);
DISPLAY 0.489362 (-6088 6137);
PAINT MONO (-6088 6137);
FORCEPROP 1 LASTPIN (-5900 6125) $PN 2
J 0
(-5938 6137);
DISPLAY 0.489362 (-5938 6137);
PAINT MONO (-5938 6137);
FORCEPROP 1 LAST MATERIAL CHIP
J 0
(-6250 6050);
DISPLAY 0.489362 (-6250 6050);
PAINT SKYBLUE (-6250 6050);
FORCEPROP 1 LAST WATTAGE 1/16W
J 0
(-5900 6075);
DISPLAY 0.489362 (-5900 6075);
PAINT SKYBLUE (-5900 6075);
FORCEPROP 1 LAST VALUE 0
J 2
(-6125 6150);
DISPLAY 0.489362 (-6125 6150);
PAINT SKYBLUE (-6125 6150);
FORCEPROP 1 LAST TOLERANCE 5%
J 0
(-5875 6150);
DISPLAY 0.489362 (-5875 6150);
PAINT SKYBLUE (-5875 6150);
FORCEPROP 1 LAST PACK_TYPE 0402LF
J 0
(-5900 6050);
DISPLAY 0.489362 (-5900 6050);
PAINT SKYBLUE (-5900 6050);
FORCEPROP 2 LAST CDS_LIB pure_quanta
J 0
(-6000 6125);
DISPLAY INVISIBLE (-6000 6125);
FORCEPROP 1 LAST PATH I44
J 0
(-6050 6275);
DISPLAY 0.978723 (-6050 6275);
PAINT WHITE (-6050 6275);
DISPLAY INVISIBLE (-6050 6275);
FORCEPROP 1 LAST PART_NUMBER CS00002JB13
J 0
(-6250 6075);
DISPLAY 0.489362 (-6250 6075);
PAINT SKYBLUE (-6250 6075);
DISPLAY INVISIBLE (-6250 6075);
FORCEADD Q_CAP..2
(-5325 5850);
FORCEPROP 1 LAST LOCATION C197
J 1
(-5325 5900);
DISPLAY 0.489362 (-5325 5900);
PAINT SKYBLUE (-5325 5900);
FORCEPROP 0 LAST $SEC 1
J 0
(-5325 5950);
DISPLAY 0.680851 (-5325 5950);
PAINT MONO (-5325 5950);
DISPLAY INVISIBLE (-5325 5950);
FORCEPROP 0 LAST CDS_SEC 1
J 0
(-5325 5950);
DISPLAY 1.021277 (-5325 5950);
DISPLAY INVISIBLE (-5325 5950);
FORCEPROP 1 LASTPIN (-5425 5850) $PN 1
J 0
(-5435 5865);
DISPLAY 0.489362 (-5435 5865);
PAINT MONO (-5435 5865);
FORCEPROP 1 LASTPIN (-5225 5850) $PN 2
J 0
(-5240 5865);
DISPLAY 0.489362 (-5240 5865);
PAINT MONO (-5240 5865);
FORCEPROP 1 LAST VALUE 1000PF
J 2
(-5500 5875);
DISPLAY 0.489362 (-5500 5875);
PAINT SKYBLUE (-5500 5875);
FORCEPROP 1 LAST MATERIAL X7R
J 0
(-5750 5800);
DISPLAY 0.489362 (-5750 5800);
PAINT SKYBLUE (-5750 5800);
FORCEPROP 1 LAST TOLERANCE 5%
J 0
(-5225 5800);
DISPLAY 0.489362 (-5225 5800);
PAINT SKYBLUE (-5225 5800);
FORCEPROP 1 LAST PACK_TYPE 0402
J 0
(-5225 5825);
DISPLAY 0.489362 (-5225 5825);
PAINT SKYBLUE (-5225 5825);
FORCEPROP 1 LAST VOLTAGE 50V
J 0
(-5175 5875);
DISPLAY 0.489362 (-5175 5875);
PAINT SKYBLUE (-5175 5875);
FORCEPROP 2 LAST CDS_LIB pure_quanta
J 0
(-5325 5850);
DISPLAY INVISIBLE (-5325 5850);
FORCEPROP 1 LAST PATH I45
J 0
(-5325 6050);
DISPLAY 0.978723 (-5325 6050);
PAINT WHITE (-5325 6050);
DISPLAY INVISIBLE (-5325 6050);
FORCEPROP 1 LAST PART_NUMBER TMP_QCH21006JB10
J 0
(-5750 5825);
DISPLAY 0.489362 (-5750 5825);
PAINT SKYBLUE (-5750 5825);
DISPLAY INVISIBLE (-5750 5825);
FORCEADD UNIVERSAL_GND..1
(-5100 5775);
FORCEPROP 3 LASTPIN (-5100 5825) SIG_NAME GND\g
J 0
(-5090 5835);
DISPLAY 0.659574 (-5090 5835);
PAINT MONO (-5090 5835);
DISPLAY INVISIBLE (-5090 5835);
FORCEPROP 2 LAST CDS_LIB pure_quanta_power
J 0
(-5100 5775);
DISPLAY INVISIBLE (-5100 5775);
FORCEPROP 1 LAST HDL_POWER GND
J 1
(-5075 5700);
DISPLAY 0.872340 (-5075 5700);
PAINT GREEN (-5075 5700);
DISPLAY INVISIBLE (-5075 5700);
FORCEPROP 1 LAST PATH I46
J 0
(-5025 5775);
DISPLAY 0.872340 (-5025 5775);
PAINT AQUA (-5025 5775);
DISPLAY INVISIBLE (-5025 5775);
FORCEADD Q_CAP..2
(-5350 6400);
FORCEPROP 1 LAST LOCATION C196
J 1
(-5350 6475);
DISPLAY 0.489362 (-5350 6475);
PAINT SKYBLUE (-5350 6475);
FORCEPROP 0 LAST $SEC 1
J 0
(-5350 6550);
DISPLAY 0.680851 (-5350 6550);
PAINT MONO (-5350 6550);
DISPLAY INVISIBLE (-5350 6550);
FORCEPROP 0 LAST CDS_SEC 1
J 0
(-5350 6550);
DISPLAY 1.021277 (-5350 6550);
DISPLAY INVISIBLE (-5350 6550);
FORCEPROP 1 LASTPIN (-5450 6400) $PN 1
J 0
(-5460 6415);
DISPLAY 0.489362 (-5460 6415);
PAINT MONO (-5460 6415);
FORCEPROP 1 LASTPIN (-5250 6400) $PN 2
J 0
(-5265 6415);
DISPLAY 0.489362 (-5265 6415);
PAINT MONO (-5265 6415);
FORCEPROP 1 LAST VOLTAGE 50V
J 0
(-5250 6450);
DISPLAY 0.489362 (-5250 6450);
PAINT SKYBLUE (-5250 6450);
FORCEPROP 1 LAST MATERIAL EMPTY
J 0
(-5625 6275);
DISPLAY 0.489362 (-5625 6275);
PAINT RED (-5625 6275);
FORCEPROP 1 LAST VALUE 1000PF
J 2
(-5475 6450);
DISPLAY 0.489362 (-5475 6450);
PAINT SKYBLUE (-5475 6450);
FORCEPROP 1 LAST PACK_TYPE 0402
J 0
(-5225 6325);
DISPLAY 0.489362 (-5225 6325);
PAINT SKYBLUE (-5225 6325);
FORCEPROP 1 LAST TOLERANCE 5%
J 0
(-5225 6275);
DISPLAY 0.489362 (-5225 6275);
PAINT SKYBLUE (-5225 6275);
FORCEPROP 2 LAST CDS_LIB pure_quanta
J 0
(-5350 6400);
DISPLAY INVISIBLE (-5350 6400);
FORCEPROP 1 LAST PATH I47
J 0
(-5350 6600);
DISPLAY 0.978723 (-5350 6600);
PAINT WHITE (-5350 6600);
DISPLAY INVISIBLE (-5350 6600);
FORCEPROP 1 LAST PART_NUMBER TMP_QCH21006JB10
J 1
(-5500 6325);
DISPLAY 0.489362 (-5500 6325);
PAINT SKYBLUE (-5500 6325);
DISPLAY INVISIBLE (-5500 6325);
FORCEADD UNIVERSAL_GND..1
(-5100 6325);
FORCEPROP 3 LASTPIN (-5100 6375) SIG_NAME GND\g
J 0
(-5090 6385);
DISPLAY 0.659574 (-5090 6385);
PAINT MONO (-5090 6385);
DISPLAY INVISIBLE (-5090 6385);
FORCEPROP 2 LAST CDS_LIB pure_quanta_power
J 0
(-5100 6325);
DISPLAY INVISIBLE (-5100 6325);
FORCEPROP 1 LAST HDL_POWER GND
J 1
(-5075 6250);
DISPLAY 0.872340 (-5075 6250);
PAINT GREEN (-5075 6250);
DISPLAY INVISIBLE (-5075 6250);
FORCEPROP 1 LAST PATH I48
J 0
(-5025 6325);
DISPLAY 0.872340 (-5025 6325);
PAINT AQUA (-5025 6325);
DISPLAY INVISIBLE (-5025 6325);
FORCEADD UNIVERSAL_GND..1
(-3475 450);
FORCEPROP 3 LASTPIN (-3475 500) SIG_NAME GND\g
J 0
(-3465 510);
DISPLAY 0.659574 (-3465 510);
PAINT MONO (-3465 510);
DISPLAY INVISIBLE (-3465 510);
FORCEPROP 2 LAST CDS_LIB pure_quanta_power
J 0
(-3475 450);
DISPLAY INVISIBLE (-3475 450);
FORCEPROP 1 LAST HDL_POWER GND
J 1
(-3450 375);
DISPLAY 0.872340 (-3450 375);
PAINT GREEN (-3450 375);
DISPLAY INVISIBLE (-3450 375);
FORCEPROP 1 LAST PATH I49
J 0
(-3400 450);
DISPLAY 0.872340 (-3400 450);
PAINT AQUA (-3400 450);
DISPLAY INVISIBLE (-3400 450);
FORCEADD UNIVERSAL_GND..1
(-6550 400);
FORCEPROP 3 LASTPIN (-6550 450) SIG_NAME GND\g
J 0
(-6540 460);
DISPLAY 0.659574 (-6540 460);
PAINT MONO (-6540 460);
DISPLAY INVISIBLE (-6540 460);
FORCEPROP 2 LAST CDS_LIB pure_quanta_power
J 0
(-6550 400);
DISPLAY INVISIBLE (-6550 400);
FORCEPROP 1 LAST HDL_POWER GND
J 1
(-6525 325);
DISPLAY 0.872340 (-6525 325);
PAINT GREEN (-6525 325);
DISPLAY INVISIBLE (-6525 325);
FORCEPROP 1 LAST PATH I5
J 0
(-6475 400);
DISPLAY 0.872340 (-6475 400);
PAINT AQUA (-6475 400);
DISPLAY INVISIBLE (-6475 400);
FORCEADD Q_CAP..1
(-3475 725);
FORCEPROP 1 LAST LOCATION PC198
J 0
(-3425 825);
DISPLAY 0.489362 (-3425 825);
PAINT SKYBLUE (-3425 825);
FORCEPROP 0 LAST $SEC 1
J 0
(-3425 850);
DISPLAY 0.680851 (-3425 850);
PAINT MONO (-3425 850);
DISPLAY INVISIBLE (-3425 850);
FORCEPROP 0 LAST CDS_SEC 1
J 0
(-3425 850);
DISPLAY 1.021277 (-3425 850);
DISPLAY INVISIBLE (-3425 850);
FORCEPROP 1 LASTPIN (-3475 825) $PN 1
J 0
(-3465 805);
DISPLAY 0.489362 (-3465 805);
PAINT MONO (-3465 805);
FORCEPROP 1 LASTPIN (-3475 625) $PN 2
J 0
(-3465 605);
DISPLAY 0.489362 (-3465 605);
PAINT MONO (-3465 605);
FORCEPROP 1 LAST PACK_TYPE 0402
J 0
(-3425 525);
DISPLAY 0.489362 (-3425 525);
PAINT SKYBLUE (-3425 525);
FORCEPROP 1 LAST VOLTAGE 50V
J 0
(-3425 725);
DISPLAY 0.489362 (-3425 725);
PAINT SKYBLUE (-3425 725);
FORCEPROP 1 LAST VALUE 470PF
J 0
(-3425 775);
DISPLAY 0.489362 (-3425 775);
PAINT SKYBLUE (-3425 775);
FORCEPROP 1 LAST TOLERANCE 10%
J 0
(-3425 675);
DISPLAY 0.489362 (-3425 675);
PAINT SKYBLUE (-3425 675);
FORCEPROP 1 LAST MATERIAL X7R
J 0
(-3425 625);
DISPLAY 0.489362 (-3425 625);
PAINT SKYBLUE (-3425 625);
FORCEPROP 2 LAST CDS_LIB pure_quanta
J 0
(-3475 725);
DISPLAY INVISIBLE (-3475 725);
FORCEPROP 1 LAST PATH I50
J 0
(-3425 875);
DISPLAY 0.978723 (-3425 875);
PAINT WHITE (-3425 875);
DISPLAY INVISIBLE (-3425 875);
FORCEPROP 1 LAST PART_NUMBER TMP_QCH14706KB18
J 0
(-3425 575);
DISPLAY 0.489362 (-3425 575);
PAINT SKYBLUE (-3425 575);
DISPLAY INVISIBLE (-3425 575);
FORCEADD OFFPAGE..4
(-3150 925);
FORCEPROP 2 LAST $XR0 208 
J 0
(-2964 925);
DISPLAY 0.638298 (-2964 925);
PAINT MONO (-2964 925);
FORCEPROP 2 LAST CDS_LIB standard
J 0
(-3150 925);
DISPLAY INVISIBLE (-3150 925);
FORCEPROP 1 LAST OFFPAGE TRUE
J 0
(-2825 800);
DISPLAY 0.872340 (-2825 800);
PAINT GREEN (-2825 800);
DISPLAY INVISIBLE (-2825 800);
FORCEPROP 1 LAST COMMENT_BODY TRUE
J 0
(-3175 825);
DISPLAY 0.872340 (-3175 825);
PAINT GREEN (-3175 825);
DISPLAY INVISIBLE (-3175 825);
FORCEPROP 2 LAST PATH I51
J 0
(-2950 975);
DISPLAY 0.680851 (-2950 975);
DISPLAY INVISIBLE (-2950 975);
FORCEADD Q_RES..1
(-3150 1225);
FORCEPROP 1 LAST LOCATION PR412
J 0
(-3200 1275);
DISPLAY 0.489362 (-3200 1275);
PAINT SKYBLUE (-3200 1275);
FORCEPROP 0 LAST $SEC 1
J 0
(-3200 1300);
DISPLAY 0.680851 (-3200 1300);
PAINT MONO (-3200 1300);
DISPLAY INVISIBLE (-3200 1300);
FORCEPROP 0 LAST CDS_SEC 1
J 0
(-3200 1300);
DISPLAY 1.021277 (-3200 1300);
DISPLAY INVISIBLE (-3200 1300);
FORCEPROP 1 LASTPIN (-3250 1225) $PN 1
J 0
(-3238 1237);
DISPLAY 0.489362 (-3238 1237);
PAINT MONO (-3238 1237);
FORCEPROP 1 LASTPIN (-3050 1225) $PN 2
J 0
(-3088 1237);
DISPLAY 0.489362 (-3088 1237);
PAINT MONO (-3088 1237);
FORCEPROP 1 LAST WATTAGE 1/16W
J 2
(-3225 1175);
DISPLAY 0.489362 (-3225 1175);
PAINT SKYBLUE (-3225 1175);
FORCEPROP 1 LAST MATERIAL CHIP
J 0
(-3475 1175);
DISPLAY 0.489362 (-3475 1175);
PAINT SKYBLUE (-3475 1175);
FORCEPROP 1 LAST TOLERANCE 5%
J 0
(-3125 1175);
DISPLAY 0.489362 (-3125 1175);
PAINT SKYBLUE (-3125 1175);
FORCEPROP 1 LAST VALUE 0
J 2
(-3150 1175);
DISPLAY 0.489362 (-3150 1175);
PAINT SKYBLUE (-3150 1175);
FORCEPROP 1 LAST PACK_TYPE 0402LF
J 0
(-3050 1175);
DISPLAY 0.489362 (-3050 1175);
PAINT SKYBLUE (-3050 1175);
FORCEPROP 2 LAST CDS_LIB pure_quanta
J 0
(-3150 1225);
DISPLAY INVISIBLE (-3150 1225);
FORCEPROP 1 LAST PATH I52
J 0
(-3200 1375);
DISPLAY 0.978723 (-3200 1375);
PAINT WHITE (-3200 1375);
DISPLAY INVISIBLE (-3200 1375);
FORCEPROP 1 LAST PART_NUMBER CS00002JB13
J 0
(-3825 1175);
DISPLAY 0.489362 (-3825 1175);
PAINT SKYBLUE (-3825 1175);
DISPLAY INVISIBLE (-3825 1175);
FORCEADD Q_RES..1
(-3150 1875);
FORCEPROP 1 LAST LOCATION PR36
J 0
(-3200 1925);
DISPLAY 0.489362 (-3200 1925);
PAINT SKYBLUE (-3200 1925);
FORCEPROP 0 LAST $SEC 1
J 0
(-3200 1975);
DISPLAY 0.680851 (-3200 1975);
PAINT MONO (-3200 1975);
DISPLAY INVISIBLE (-3200 1975);
FORCEPROP 0 LAST CDS_SEC 1
J 0
(-3200 1975);
DISPLAY 1.021277 (-3200 1975);
DISPLAY INVISIBLE (-3200 1975);
FORCEPROP 1 LASTPIN (-3250 1875) $PN 1
J 0
(-3238 1887);
DISPLAY 0.489362 (-3238 1887);
PAINT MONO (-3238 1887);
FORCEPROP 1 LASTPIN (-3050 1875) $PN 2
J 0
(-3088 1887);
DISPLAY 0.489362 (-3088 1887);
PAINT MONO (-3088 1887);
FORCEPROP 1 LAST MATERIAL CHIP
J 0
(-3475 1825);
DISPLAY 0.489362 (-3475 1825);
PAINT SKYBLUE (-3475 1825);
FORCEPROP 1 LAST TOLERANCE 5%
J 0
(-3125 1825);
DISPLAY 0.489362 (-3125 1825);
PAINT SKYBLUE (-3125 1825);
FORCEPROP 1 LAST PACK_TYPE 0402LF
J 0
(-3050 1825);
DISPLAY 0.489362 (-3050 1825);
PAINT SKYBLUE (-3050 1825);
FORCEPROP 1 LAST VALUE 0
J 2
(-3150 1825);
DISPLAY 0.489362 (-3150 1825);
PAINT SKYBLUE (-3150 1825);
FORCEPROP 1 LAST WATTAGE 1/16W
J 2
(-3225 1825);
DISPLAY 0.489362 (-3225 1825);
PAINT SKYBLUE (-3225 1825);
FORCEPROP 2 LAST CDS_LIB pure_quanta
J 0
(-3150 1875);
DISPLAY INVISIBLE (-3150 1875);
FORCEPROP 1 LAST PATH I53
J 0
(-3200 2025);
DISPLAY 0.978723 (-3200 2025);
PAINT WHITE (-3200 2025);
DISPLAY INVISIBLE (-3200 2025);
FORCEPROP 1 LAST PART_NUMBER CS00002JB13
J 0
(-3825 1825);
DISPLAY 0.489362 (-3825 1825);
PAINT SKYBLUE (-3825 1825);
DISPLAY INVISIBLE (-3825 1825);
FORCEADD UNIVERSAL_GND..1
(-2700 1150);
FORCEPROP 3 LASTPIN (-2700 1200) SIG_NAME GND\g
J 0
(-2690 1210);
DISPLAY 0.659574 (-2690 1210);
PAINT MONO (-2690 1210);
DISPLAY INVISIBLE (-2690 1210);
FORCEPROP 2 LAST CDS_LIB pure_quanta_power
J 0
(-2700 1150);
DISPLAY INVISIBLE (-2700 1150);
FORCEPROP 1 LAST HDL_POWER GND
J 1
(-2675 1075);
DISPLAY 0.872340 (-2675 1075);
PAINT GREEN (-2675 1075);
DISPLAY INVISIBLE (-2675 1075);
FORCEPROP 1 LAST PATH I54
J 0
(-2625 1150);
DISPLAY 0.872340 (-2625 1150);
PAINT AQUA (-2625 1150);
DISPLAY INVISIBLE (-2625 1150);
FORCEADD UNIVERSAL_GND..1
(-2700 1800);
FORCEPROP 3 LASTPIN (-2700 1850) SIG_NAME GND\g
J 0
(-2690 1860);
DISPLAY 0.659574 (-2690 1860);
PAINT MONO (-2690 1860);
DISPLAY INVISIBLE (-2690 1860);
FORCEPROP 2 LAST CDS_LIB pure_quanta_power
J 0
(-2700 1800);
DISPLAY INVISIBLE (-2700 1800);
FORCEPROP 1 LAST HDL_POWER GND
J 1
(-2675 1725);
DISPLAY 0.872340 (-2675 1725);
PAINT GREEN (-2675 1725);
DISPLAY INVISIBLE (-2675 1725);
FORCEPROP 1 LAST PATH I55
J 0
(-2625 1800);
DISPLAY 0.872340 (-2625 1800);
PAINT AQUA (-2625 1800);
DISPLAY INVISIBLE (-2625 1800);
FORCEADD UNIVERSAL_GND..1
(-2175 1200);
FORCEPROP 3 LASTPIN (-2175 1250) SIG_NAME GND\g
J 0
(-2165 1260);
DISPLAY 0.659574 (-2165 1260);
PAINT MONO (-2165 1260);
DISPLAY INVISIBLE (-2165 1260);
FORCEPROP 2 LAST CDS_LIB pure_quanta_power
J 0
(-2175 1200);
DISPLAY INVISIBLE (-2175 1200);
FORCEPROP 1 LAST HDL_POWER GND
J 1
(-2150 1125);
DISPLAY 0.872340 (-2150 1125);
PAINT GREEN (-2150 1125);
DISPLAY INVISIBLE (-2150 1125);
FORCEPROP 1 LAST PATH I56
J 0
(-2100 1200);
DISPLAY 0.872340 (-2100 1200);
PAINT AQUA (-2100 1200);
DISPLAY INVISIBLE (-2100 1200);
FORCEADD Q_RES..2
(-2175 1425);
FORCEPROP 1 LAST LOCATION PR127
J 0
(-2130 1550);
DISPLAY 0.489362 (-2130 1550);
PAINT SKYBLUE (-2130 1550);
FORCEPROP 0 LAST $SEC 1
J 0
(-2125 1575);
DISPLAY 0.680851 (-2125 1575);
PAINT MONO (-2125 1575);
DISPLAY INVISIBLE (-2125 1575);
FORCEPROP 0 LAST CDS_SEC 1
J 0
(-2125 1575);
DISPLAY 1.021277 (-2125 1575);
DISPLAY INVISIBLE (-2125 1575);
FORCEPROP 1 LASTPIN (-2175 1525) $PN 1
J 0
(-2170 1487);
DISPLAY 0.489362 (-2170 1487);
PAINT MONO (-2170 1487);
FORCEPROP 1 LASTPIN (-2175 1325) $PN 2
J 0
(-2170 1335);
DISPLAY 0.489362 (-2170 1335);
PAINT MONO (-2170 1335);
FORCEPROP 1 LAST WATTAGE 1/16W
J 0
(-2135 1400);
DISPLAY 0.489362 (-2135 1400);
PAINT SKYBLUE (-2135 1400);
FORCEPROP 1 LAST MATERIAL EMPTY
J 0
(-2135 1350);
DISPLAY 0.489362 (-2135 1350);
PAINT RED (-2135 1350);
FORCEPROP 1 LAST TOLERANCE 5%
J 0
(-2130 1450);
DISPLAY 0.489362 (-2130 1450);
PAINT SKYBLUE (-2130 1450);
FORCEPROP 1 LAST VALUE 0
J 0
(-2130 1500);
DISPLAY 0.489362 (-2130 1500);
PAINT SKYBLUE (-2130 1500);
FORCEPROP 1 LAST PACK_TYPE 0402LF
J 0
(-2135 1250);
DISPLAY 0.489362 (-2135 1250);
PAINT SKYBLUE (-2135 1250);
FORCEPROP 2 LAST CDS_LIB pure_quanta
J 0
(-2175 1425);
DISPLAY INVISIBLE (-2175 1425);
FORCEPROP 1 LAST PATH I57
J 0
(-2125 1600);
DISPLAY 0.978723 (-2125 1600);
PAINT WHITE (-2125 1600);
DISPLAY INVISIBLE (-2125 1600);
FORCEPROP 1 LAST PART_NUMBER CS00002JB13
J 0
(-2135 1300);
DISPLAY 0.489362 (-2135 1300);
PAINT SKYBLUE (-2135 1300);
DISPLAY INVISIBLE (-2135 1300);
FORCEADD Q_RES..1
(-3150 2325);
FORCEPROP 1 LAST LOCATION PR419
J 0
(-3200 2375);
DISPLAY 0.489362 (-3200 2375);
PAINT SKYBLUE (-3200 2375);
FORCEPROP 0 LAST $SEC 1
J 0
(-3200 2400);
DISPLAY 0.680851 (-3200 2400);
PAINT MONO (-3200 2400);
DISPLAY INVISIBLE (-3200 2400);
FORCEPROP 0 LAST CDS_SEC 1
J 0
(-3200 2400);
DISPLAY 1.021277 (-3200 2400);
DISPLAY INVISIBLE (-3200 2400);
FORCEPROP 1 LASTPIN (-3250 2325) $PN 1
J 0
(-3238 2337);
DISPLAY 0.489362 (-3238 2337);
PAINT MONO (-3238 2337);
FORCEPROP 1 LASTPIN (-3050 2325) $PN 2
J 0
(-3088 2337);
DISPLAY 0.489362 (-3088 2337);
PAINT MONO (-3088 2337);
FORCEPROP 1 LAST WATTAGE 1/16W
J 2
(-3225 2275);
DISPLAY 0.489362 (-3225 2275);
PAINT SKYBLUE (-3225 2275);
FORCEPROP 1 LAST MATERIAL CHIP
J 0
(-3475 2275);
DISPLAY 0.489362 (-3475 2275);
PAINT SKYBLUE (-3475 2275);
FORCEPROP 1 LAST TOLERANCE 5%
J 0
(-3125 2275);
DISPLAY 0.489362 (-3125 2275);
PAINT SKYBLUE (-3125 2275);
FORCEPROP 1 LAST VALUE 0
J 2
(-3150 2275);
DISPLAY 0.489362 (-3150 2275);
PAINT SKYBLUE (-3150 2275);
FORCEPROP 1 LAST PACK_TYPE 0402LF
J 0
(-3050 2275);
DISPLAY 0.489362 (-3050 2275);
PAINT SKYBLUE (-3050 2275);
FORCEPROP 2 LAST CDS_LIB pure_quanta
J 0
(-3150 2325);
DISPLAY INVISIBLE (-3150 2325);
FORCEPROP 1 LAST PATH I58
J 0
(-3200 2475);
DISPLAY 0.978723 (-3200 2475);
PAINT WHITE (-3200 2475);
DISPLAY INVISIBLE (-3200 2475);
FORCEPROP 1 LAST PART_NUMBER CS00002JB13
J 0
(-3825 2275);
DISPLAY 0.489362 (-3825 2275);
PAINT SKYBLUE (-3825 2275);
DISPLAY INVISIBLE (-3825 2275);
FORCEADD Q_RES..1
(-3150 2775);
FORCEPROP 1 LAST LOCATION PR35
J 0
(-3200 2825);
DISPLAY 0.489362 (-3200 2825);
PAINT SKYBLUE (-3200 2825);
FORCEPROP 0 LAST $SEC 1
J 0
(-3200 2875);
DISPLAY 0.680851 (-3200 2875);
PAINT MONO (-3200 2875);
DISPLAY INVISIBLE (-3200 2875);
FORCEPROP 0 LAST CDS_SEC 1
J 0
(-3200 2875);
DISPLAY 1.021277 (-3200 2875);
DISPLAY INVISIBLE (-3200 2875);
FORCEPROP 1 LASTPIN (-3250 2775) $PN 1
J 0
(-3238 2787);
DISPLAY 0.489362 (-3238 2787);
PAINT MONO (-3238 2787);
FORCEPROP 1 LASTPIN (-3050 2775) $PN 2
J 0
(-3088 2787);
DISPLAY 0.489362 (-3088 2787);
PAINT MONO (-3088 2787);
FORCEPROP 1 LAST PACK_TYPE 0402LF
J 0
(-3050 2725);
DISPLAY 0.489362 (-3050 2725);
PAINT SKYBLUE (-3050 2725);
FORCEPROP 1 LAST WATTAGE 1/16W
J 2
(-3225 2725);
DISPLAY 0.489362 (-3225 2725);
PAINT SKYBLUE (-3225 2725);
FORCEPROP 1 LAST MATERIAL CHIP
J 0
(-3475 2725);
DISPLAY 0.489362 (-3475 2725);
PAINT SKYBLUE (-3475 2725);
FORCEPROP 1 LAST TOLERANCE 5%
J 0
(-3125 2725);
DISPLAY 0.489362 (-3125 2725);
PAINT SKYBLUE (-3125 2725);
FORCEPROP 1 LAST VALUE 0
J 2
(-3150 2725);
DISPLAY 0.489362 (-3150 2725);
PAINT SKYBLUE (-3150 2725);
FORCEPROP 2 LAST CDS_LIB pure_quanta
J 0
(-3150 2775);
DISPLAY INVISIBLE (-3150 2775);
FORCEPROP 1 LAST PATH I59
J 0
(-3200 2925);
DISPLAY 0.978723 (-3200 2925);
PAINT WHITE (-3200 2925);
DISPLAY INVISIBLE (-3200 2925);
FORCEPROP 1 LAST PART_NUMBER CS00002JB13
J 0
(-3825 2725);
DISPLAY 0.489362 (-3825 2725);
PAINT SKYBLUE (-3825 2725);
DISPLAY INVISIBLE (-3825 2725);
FORCEADD Q_RES..2
(-6550 675);
FORCEPROP 1 LAST LOCATION PR3
J 0
(-6500 775);
DISPLAY 0.489362 (-6500 775);
PAINT SKYBLUE (-6500 775);
FORCEPROP 2 LAST SEC 1
J 0
(-6500 900);
DISPLAY 0.680851 (-6500 900);
PAINT MONO (-6500 900);
DISPLAY INVISIBLE (-6500 900);
FORCEPROP 1 LASTPIN (-6550 775) $PN 1
J 0
(-6545 737);
DISPLAY 0.489362 (-6545 737);
PAINT MONO (-6545 737);
FORCEPROP 1 LASTPIN (-6550 575) $PN 2
J 0
(-6545 585);
DISPLAY 0.489362 (-6545 585);
PAINT MONO (-6545 585);
FORCEPROP 1 LAST MATERIAL CHIP
J 0
(-6500 575);
DISPLAY 0.489362 (-6500 575);
PAINT SKYBLUE (-6500 575);
FORCEPROP 1 LAST VALUE 10K
J 0
(-6500 725);
DISPLAY 0.489362 (-6500 725);
PAINT SKYBLUE (-6500 725);
FORCEPROP 1 LAST PACK_TYPE 0402LF
J 0
(-6500 475);
DISPLAY 0.489362 (-6500 475);
PAINT SKYBLUE (-6500 475);
FORCEPROP 1 LAST TOLERANCE 1%
J 0
(-6500 675);
DISPLAY 0.489362 (-6500 675);
PAINT SKYBLUE (-6500 675);
FORCEPROP 1 LAST WATTAGE 1/16W
J 0
(-6500 625);
DISPLAY 0.489362 (-6500 625);
PAINT SKYBLUE (-6500 625);
FORCEPROP 2 LAST CDS_LIB pure_quanta
J 0
(-6550 675);
DISPLAY INVISIBLE (-6550 675);
FORCEPROP 2 LAST SEC_TYPE 0402LF
J 0
(-6500 900);
DISPLAY 1.021277 (-6500 900);
DISPLAY INVISIBLE (-6500 900);
FORCEPROP 1 LAST PATH I6
J 0
(-6500 850);
DISPLAY 0.978723 (-6500 850);
PAINT WHITE (-6500 850);
DISPLAY INVISIBLE (-6500 850);
FORCEPROP 1 LAST PART_NUMBER CS31002FB08
J 0
(-6500 525);
DISPLAY 0.489362 (-6500 525);
PAINT SKYBLUE (-6500 525);
DISPLAY INVISIBLE (-6500 525);
FORCEADD Q_RES..1
(-3150 3225);
FORCEPROP 1 LAST LOCATION PR34
J 0
(-3200 3275);
DISPLAY 0.489362 (-3200 3275);
PAINT SKYBLUE (-3200 3275);
FORCEPROP 0 LAST $SEC 1
J 0
(-3200 3325);
DISPLAY 0.680851 (-3200 3325);
PAINT MONO (-3200 3325);
DISPLAY INVISIBLE (-3200 3325);
FORCEPROP 0 LAST CDS_SEC 1
J 0
(-3200 3325);
DISPLAY 1.021277 (-3200 3325);
DISPLAY INVISIBLE (-3200 3325);
FORCEPROP 1 LASTPIN (-3250 3225) $PN 1
J 0
(-3238 3237);
DISPLAY 0.489362 (-3238 3237);
PAINT MONO (-3238 3237);
FORCEPROP 1 LASTPIN (-3050 3225) $PN 2
J 0
(-3088 3237);
DISPLAY 0.489362 (-3088 3237);
PAINT MONO (-3088 3237);
FORCEPROP 1 LAST WATTAGE 1/16W
J 2
(-3225 3175);
DISPLAY 0.489362 (-3225 3175);
PAINT SKYBLUE (-3225 3175);
FORCEPROP 1 LAST MATERIAL CHIP
J 0
(-3475 3175);
DISPLAY 0.489362 (-3475 3175);
PAINT SKYBLUE (-3475 3175);
FORCEPROP 1 LAST TOLERANCE 5%
J 0
(-3125 3175);
DISPLAY 0.489362 (-3125 3175);
PAINT SKYBLUE (-3125 3175);
FORCEPROP 1 LAST VALUE 0
J 2
(-3150 3175);
DISPLAY 0.489362 (-3150 3175);
PAINT SKYBLUE (-3150 3175);
FORCEPROP 1 LAST PACK_TYPE 0402LF
J 0
(-3050 3175);
DISPLAY 0.489362 (-3050 3175);
PAINT SKYBLUE (-3050 3175);
FORCEPROP 2 LAST CDS_LIB pure_quanta
J 0
(-3150 3225);
DISPLAY INVISIBLE (-3150 3225);
FORCEPROP 1 LAST PATH I60
J 0
(-3200 3375);
DISPLAY 0.978723 (-3200 3375);
PAINT WHITE (-3200 3375);
DISPLAY INVISIBLE (-3200 3375);
FORCEPROP 1 LAST PART_NUMBER CS00002JB13
J 0
(-3825 3175);
DISPLAY 0.489362 (-3825 3175);
PAINT SKYBLUE (-3825 3175);
DISPLAY INVISIBLE (-3825 3175);
FORCEADD Q_RES..1
(-3150 3675);
FORCEPROP 1 LAST LOCATION PR33
J 0
(-3200 3725);
DISPLAY 0.489362 (-3200 3725);
PAINT SKYBLUE (-3200 3725);
FORCEPROP 0 LAST $SEC 1
J 0
(-3200 3775);
DISPLAY 0.680851 (-3200 3775);
PAINT MONO (-3200 3775);
DISPLAY INVISIBLE (-3200 3775);
FORCEPROP 0 LAST CDS_SEC 1
J 0
(-3200 3775);
DISPLAY 1.021277 (-3200 3775);
DISPLAY INVISIBLE (-3200 3775);
FORCEPROP 1 LASTPIN (-3250 3675) $PN 1
J 0
(-3238 3687);
DISPLAY 0.489362 (-3238 3687);
PAINT MONO (-3238 3687);
FORCEPROP 1 LASTPIN (-3050 3675) $PN 2
J 0
(-3088 3687);
DISPLAY 0.489362 (-3088 3687);
PAINT MONO (-3088 3687);
FORCEPROP 1 LAST WATTAGE 1/16W
J 2
(-3225 3625);
DISPLAY 0.489362 (-3225 3625);
PAINT SKYBLUE (-3225 3625);
FORCEPROP 1 LAST MATERIAL CHIP
J 0
(-3475 3625);
DISPLAY 0.489362 (-3475 3625);
PAINT SKYBLUE (-3475 3625);
FORCEPROP 1 LAST TOLERANCE 5%
J 0
(-3125 3625);
DISPLAY 0.489362 (-3125 3625);
PAINT SKYBLUE (-3125 3625);
FORCEPROP 1 LAST VALUE 0
J 2
(-3150 3625);
DISPLAY 0.489362 (-3150 3625);
PAINT SKYBLUE (-3150 3625);
FORCEPROP 1 LAST PACK_TYPE 0402LF
J 0
(-3050 3625);
DISPLAY 0.489362 (-3050 3625);
PAINT SKYBLUE (-3050 3625);
FORCEPROP 2 LAST CDS_LIB pure_quanta
J 0
(-3150 3675);
DISPLAY INVISIBLE (-3150 3675);
FORCEPROP 1 LAST PATH I61
J 0
(-3200 3825);
DISPLAY 0.978723 (-3200 3825);
PAINT WHITE (-3200 3825);
DISPLAY INVISIBLE (-3200 3825);
FORCEPROP 1 LAST PART_NUMBER CS00002JB13
J 0
(-3825 3625);
DISPLAY 0.489362 (-3825 3625);
PAINT SKYBLUE (-3825 3625);
DISPLAY INVISIBLE (-3825 3625);
FORCEADD UNIVERSAL_GND..1
(-2700 2250);
FORCEPROP 3 LASTPIN (-2700 2300) SIG_NAME GND\g
J 0
(-2690 2310);
DISPLAY 0.659574 (-2690 2310);
PAINT MONO (-2690 2310);
DISPLAY INVISIBLE (-2690 2310);
FORCEPROP 2 LAST CDS_LIB pure_quanta_power
J 0
(-2700 2250);
DISPLAY INVISIBLE (-2700 2250);
FORCEPROP 1 LAST HDL_POWER GND
J 1
(-2675 2175);
DISPLAY 0.872340 (-2675 2175);
PAINT GREEN (-2675 2175);
DISPLAY INVISIBLE (-2675 2175);
FORCEPROP 1 LAST PATH I62
J 0
(-2625 2250);
DISPLAY 0.872340 (-2625 2250);
PAINT AQUA (-2625 2250);
DISPLAY INVISIBLE (-2625 2250);
FORCEADD UNIVERSAL_GND..1
(-2700 2700);
FORCEPROP 3 LASTPIN (-2700 2750) SIG_NAME GND\g
J 0
(-2690 2760);
DISPLAY 0.659574 (-2690 2760);
PAINT MONO (-2690 2760);
DISPLAY INVISIBLE (-2690 2760);
FORCEPROP 2 LAST CDS_LIB pure_quanta_power
J 0
(-2700 2700);
DISPLAY INVISIBLE (-2700 2700);
FORCEPROP 1 LAST HDL_POWER GND
J 1
(-2675 2625);
DISPLAY 0.872340 (-2675 2625);
PAINT GREEN (-2675 2625);
DISPLAY INVISIBLE (-2675 2625);
FORCEPROP 1 LAST PATH I63
J 0
(-2625 2700);
DISPLAY 0.872340 (-2625 2700);
PAINT AQUA (-2625 2700);
DISPLAY INVISIBLE (-2625 2700);
FORCEADD UNIVERSAL_GND..1
(-2700 3150);
FORCEPROP 3 LASTPIN (-2700 3200) SIG_NAME GND\g
J 0
(-2690 3210);
DISPLAY 0.659574 (-2690 3210);
PAINT MONO (-2690 3210);
DISPLAY INVISIBLE (-2690 3210);
FORCEPROP 2 LAST CDS_LIB pure_quanta_power
J 0
(-2700 3150);
DISPLAY INVISIBLE (-2700 3150);
FORCEPROP 1 LAST HDL_POWER GND
J 1
(-2675 3075);
DISPLAY 0.872340 (-2675 3075);
PAINT GREEN (-2675 3075);
DISPLAY INVISIBLE (-2675 3075);
FORCEPROP 1 LAST PATH I64
J 0
(-2625 3150);
DISPLAY 0.872340 (-2625 3150);
PAINT AQUA (-2625 3150);
DISPLAY INVISIBLE (-2625 3150);
FORCEADD UNIVERSAL_GND..1
(-2700 3600);
FORCEPROP 3 LASTPIN (-2700 3650) SIG_NAME GND\g
J 0
(-2690 3660);
DISPLAY 0.659574 (-2690 3660);
PAINT MONO (-2690 3660);
DISPLAY INVISIBLE (-2690 3660);
FORCEPROP 2 LAST CDS_LIB pure_quanta_power
J 0
(-2700 3600);
DISPLAY INVISIBLE (-2700 3600);
FORCEPROP 1 LAST HDL_POWER GND
J 1
(-2675 3525);
DISPLAY 0.872340 (-2675 3525);
PAINT GREEN (-2675 3525);
DISPLAY INVISIBLE (-2675 3525);
FORCEPROP 1 LAST PATH I65
J 0
(-2625 3600);
DISPLAY 0.872340 (-2625 3600);
PAINT AQUA (-2625 3600);
DISPLAY INVISIBLE (-2625 3600);
FORCEADD UNIVERSAL_GND..1
(-2700 4050);
FORCEPROP 3 LASTPIN (-2700 4100) SIG_NAME GND\g
J 0
(-2690 4110);
DISPLAY 0.659574 (-2690 4110);
PAINT MONO (-2690 4110);
DISPLAY INVISIBLE (-2690 4110);
FORCEPROP 2 LAST CDS_LIB pure_quanta_power
J 0
(-2700 4050);
DISPLAY INVISIBLE (-2700 4050);
FORCEPROP 1 LAST HDL_POWER GND
J 1
(-2675 3975);
DISPLAY 0.872340 (-2675 3975);
PAINT GREEN (-2675 3975);
DISPLAY INVISIBLE (-2675 3975);
FORCEPROP 1 LAST PATH I66
J 0
(-2625 4050);
DISPLAY 0.872340 (-2625 4050);
PAINT AQUA (-2625 4050);
DISPLAY INVISIBLE (-2625 4050);
FORCEADD Q_RES..1
(-1700 1625);
FORCEPROP 1 LAST LOCATION PR129
J 0
(-1750 1675);
DISPLAY 0.489362 (-1750 1675);
PAINT SKYBLUE (-1750 1675);
FORCEPROP 0 LAST $SEC 1
J 0
(-1750 1700);
DISPLAY 0.680851 (-1750 1700);
PAINT MONO (-1750 1700);
DISPLAY INVISIBLE (-1750 1700);
FORCEPROP 0 LAST CDS_SEC 1
J 0
(-1750 1700);
DISPLAY 1.021277 (-1750 1700);
DISPLAY INVISIBLE (-1750 1700);
FORCEPROP 1 LASTPIN (-1800 1625) $PN 1
J 0
(-1788 1637);
DISPLAY 0.489362 (-1788 1637);
PAINT MONO (-1788 1637);
FORCEPROP 1 LASTPIN (-1600 1625) $PN 2
J 0
(-1638 1637);
DISPLAY 0.489362 (-1638 1637);
PAINT MONO (-1638 1637);
FORCEPROP 1 LAST WATTAGE 1/16W
J 0
(-1600 1575);
DISPLAY 0.489362 (-1600 1575);
PAINT SKYBLUE (-1600 1575);
FORCEPROP 1 LAST TOLERANCE 5%
J 0
(-1575 1650);
DISPLAY 0.489362 (-1575 1650);
PAINT SKYBLUE (-1575 1650);
FORCEPROP 1 LAST PACK_TYPE 0402LF
J 0
(-1600 1550);
DISPLAY 0.489362 (-1600 1550);
PAINT SKYBLUE (-1600 1550);
FORCEPROP 1 LAST VALUE 0
J 2
(-1825 1650);
DISPLAY 0.489362 (-1825 1650);
PAINT SKYBLUE (-1825 1650);
FORCEPROP 1 LAST MATERIAL EMPTY
J 0
(-1950 1550);
DISPLAY 0.489362 (-1950 1550);
PAINT RED (-1950 1550);
FORCEPROP 2 LAST CDS_LIB pure_quanta
J 0
(-1700 1625);
DISPLAY INVISIBLE (-1700 1625);
FORCEPROP 1 LAST PATH I67
J 0
(-1750 1775);
DISPLAY 0.978723 (-1750 1775);
PAINT WHITE (-1750 1775);
DISPLAY INVISIBLE (-1750 1775);
FORCEPROP 1 LAST PART_NUMBER CS00002JB13
J 0
(-1950 1575);
DISPLAY 0.489362 (-1950 1575);
PAINT SKYBLUE (-1950 1575);
DISPLAY INVISIBLE (-1950 1575);
FORCEADD Q_RES..1
(-1750 1850);
FORCEPROP 1 LAST LOCATION PR128
J 0
(-1800 1900);
DISPLAY 0.489362 (-1800 1900);
PAINT SKYBLUE (-1800 1900);
FORCEPROP 0 LAST $SEC 1
J 0
(-1800 1925);
DISPLAY 0.680851 (-1800 1925);
PAINT MONO (-1800 1925);
DISPLAY INVISIBLE (-1800 1925);
FORCEPROP 0 LAST CDS_SEC 1
J 0
(-1700 2025);
DISPLAY 1.021277 (-1700 2025);
DISPLAY INVISIBLE (-1700 2025);
FORCEPROP 1 LASTPIN (-1850 1850) $PN 1
J 0
(-1838 1862);
DISPLAY 0.489362 (-1838 1862);
PAINT MONO (-1838 1862);
FORCEPROP 1 LASTPIN (-1650 1850) $PN 2
J 0
(-1688 1862);
DISPLAY 0.489362 (-1688 1862);
PAINT MONO (-1688 1862);
FORCEPROP 1 LAST WATTAGE 1/16W
J 0
(-1575 1775);
DISPLAY 0.489362 (-1575 1775);
PAINT SKYBLUE (-1575 1775);
FORCEPROP 1 LAST MATERIAL EMPTY
J 0
(-1975 1775);
DISPLAY 0.489362 (-1975 1775);
PAINT RED (-1975 1775);
FORCEPROP 1 LAST TOLERANCE 1%
J 0
(-1625 1875);
DISPLAY 0.489362 (-1625 1875);
PAINT SKYBLUE (-1625 1875);
FORCEPROP 1 LAST PACK_TYPE 0402LF
J 0
(-1575 1800);
DISPLAY 0.489362 (-1575 1800);
PAINT SKYBLUE (-1575 1800);
FORCEPROP 1 LAST VALUE 1K
J 2
(-1875 1875);
DISPLAY 0.489362 (-1875 1875);
PAINT SKYBLUE (-1875 1875);
FORCEPROP 2 LAST CDS_LIB pure_quanta
J 0
(-1750 1850);
DISPLAY INVISIBLE (-1750 1850);
FORCEPROP 1 LAST PATH I68
J 0
(-1800 2000);
DISPLAY 0.978723 (-1800 2000);
PAINT WHITE (-1800 2000);
DISPLAY INVISIBLE (-1800 2000);
FORCEPROP 1 LAST PART_NUMBER CS21002FB06
J 0
(-1975 1800);
DISPLAY 0.489362 (-1975 1800);
PAINT SKYBLUE (-1975 1800);
DISPLAY INVISIBLE (-1975 1800);
FORCEADD VCC_CORE..1
(-1400 2000);
FORCEPROP 3 LASTPIN (-1400 1950) SIG_NAME PVDD18_S5_P0\g
J 0
(-1390 1960);
DISPLAY 0.659574 (-1390 1960);
PAINT MONO (-1390 1960);
DISPLAY INVISIBLE (-1390 1960);
FORCEPROP 1 LAST HDL_POWER PVDD18_S5_P0
J 1
(-1400 2050);
DISPLAY 0.489362 (-1400 2050);
PAINT GREEN (-1400 2050);
FORCEPROP 2 LAST CDS_LIB pure_quanta_power
J 0
(-1400 2000);
DISPLAY INVISIBLE (-1400 2000);
FORCEPROP 1 LAST PATH I69
J 0
(-1350 2025);
DISPLAY 0.872340 (-1350 2025);
PAINT AQUA (-1350 2025);
DISPLAY INVISIBLE (-1350 2025);
FORCEADD VCC_CORE..1
(-6275 750);
FORCEPROP 3 LASTPIN (-6275 700) SIG_NAME P12V_AUX\g
J 0
(-6265 710);
DISPLAY 0.659574 (-6265 710);
PAINT MONO (-6265 710);
DISPLAY INVISIBLE (-6265 710);
FORCEPROP 1 LAST HDL_POWER P12V_AUX
J 1
(-6275 800);
DISPLAY 0.489362 (-6275 800);
PAINT GREEN (-6275 800);
FORCEPROP 2 LAST CDS_LIB pure_quanta_power
J 0
(-6275 750);
DISPLAY INVISIBLE (-6275 750);
FORCEPROP 1 LAST PATH I7
J 0
(-6225 775);
DISPLAY 0.872340 (-6225 775);
PAINT AQUA (-6225 775);
DISPLAY INVISIBLE (-6225 775);
FORCEADD OFFPAGE..4
(-850 1625);
FORCEPROP 2 LAST $XR0 81 
J 0
(-664 1625);
DISPLAY 0.638298 (-664 1625);
PAINT MONO (-664 1625);
FORCEPROP 2 LAST CDS_LIB standard
J 2
(-850 1625);
DISPLAY INVISIBLE (-850 1625);
FORCEPROP 1 LAST OFFPAGE TRUE
J 0
(-525 1500);
DISPLAY 0.872340 (-525 1500);
PAINT GREEN (-525 1500);
DISPLAY INVISIBLE (-525 1500);
FORCEPROP 1 LAST COMMENT_BODY TRUE
J 0
(-875 1525);
DISPLAY 0.872340 (-875 1525);
PAINT GREEN (-875 1525);
DISPLAY INVISIBLE (-875 1525);
FORCEPROP 2 LAST PATH I70
J 0
(-650 1675);
DISPLAY 0.680851 (-650 1675);
DISPLAY INVISIBLE (-650 1675);
FORCEADD Q_RES..1
(-3125 4125);
FORCEPROP 1 LAST LOCATION PR37
J 0
(-3175 4175);
DISPLAY 0.489362 (-3175 4175);
PAINT SKYBLUE (-3175 4175);
FORCEPROP 0 LAST $SEC 1
J 0
(-3175 4225);
DISPLAY 0.680851 (-3175 4225);
PAINT MONO (-3175 4225);
DISPLAY INVISIBLE (-3175 4225);
FORCEPROP 0 LAST CDS_SEC 1
J 0
(-3175 4225);
DISPLAY 1.021277 (-3175 4225);
DISPLAY INVISIBLE (-3175 4225);
FORCEPROP 1 LASTPIN (-3225 4125) $PN 1
J 0
(-3213 4137);
DISPLAY 0.489362 (-3213 4137);
PAINT MONO (-3213 4137);
FORCEPROP 1 LASTPIN (-3025 4125) $PN 2
J 0
(-3063 4137);
DISPLAY 0.489362 (-3063 4137);
PAINT MONO (-3063 4137);
FORCEPROP 1 LAST WATTAGE 1/16W
J 2
(-3200 4075);
DISPLAY 0.489362 (-3200 4075);
PAINT SKYBLUE (-3200 4075);
FORCEPROP 1 LAST MATERIAL CHIP
J 0
(-3450 4075);
DISPLAY 0.489362 (-3450 4075);
PAINT SKYBLUE (-3450 4075);
FORCEPROP 1 LAST TOLERANCE 5%
J 0
(-3100 4075);
DISPLAY 0.489362 (-3100 4075);
PAINT SKYBLUE (-3100 4075);
FORCEPROP 1 LAST VALUE 0
J 2
(-3125 4075);
DISPLAY 0.489362 (-3125 4075);
PAINT SKYBLUE (-3125 4075);
FORCEPROP 1 LAST PACK_TYPE 0402LF
J 0
(-3025 4075);
DISPLAY 0.489362 (-3025 4075);
PAINT SKYBLUE (-3025 4075);
FORCEPROP 2 LAST CDS_LIB pure_quanta
J 0
(-3125 4125);
DISPLAY INVISIBLE (-3125 4125);
FORCEPROP 1 LAST PATH I71
J 0
(-3175 4275);
DISPLAY 0.978723 (-3175 4275);
PAINT WHITE (-3175 4275);
DISPLAY INVISIBLE (-3175 4275);
FORCEPROP 1 LAST PART_NUMBER CS00002JB13
J 0
(-3800 4075);
DISPLAY 0.489362 (-3800 4075);
PAINT SKYBLUE (-3800 4075);
DISPLAY INVISIBLE (-3800 4075);
FORCEADD OFFPAGE..2
(-3125 4675);
FORCEPROP 2 LAST $XR0 208 
J 0
(-2936 4675);
DISPLAY 0.638298 (-2936 4675);
PAINT MONO (-2936 4675);
FORCEPROP 2 LAST CDS_LIB standard
J 0
(-3125 4675);
DISPLAY INVISIBLE (-3125 4675);
FORCEPROP 1 LAST OFFPAGE TRUE
J 0
(-2800 4550);
DISPLAY 0.872340 (-2800 4550);
PAINT GREEN (-2800 4550);
DISPLAY INVISIBLE (-2800 4550);
FORCEPROP 1 LAST COMMENT_BODY TRUE
J 0
(-3170 4580);
DISPLAY 0.872340 (-3170 4580);
PAINT GREEN (-3170 4580);
DISPLAY INVISIBLE (-3170 4580);
FORCEPROP 2 LAST PATH I72
J 0
(-2925 4725);
DISPLAY 0.680851 (-2925 4725);
DISPLAY INVISIBLE (-2925 4725);
FORCEADD OFFPAGE..4
(-3125 4575);
FORCEPROP 2 LAST $XR0 208 
J 0
(-2939 4575);
DISPLAY 0.638298 (-2939 4575);
PAINT MONO (-2939 4575);
FORCEPROP 2 LAST CDS_LIB standard
J 0
(-3125 4575);
DISPLAY INVISIBLE (-3125 4575);
FORCEPROP 1 LAST OFFPAGE TRUE
J 0
(-2800 4450);
DISPLAY 0.872340 (-2800 4450);
PAINT GREEN (-2800 4450);
DISPLAY INVISIBLE (-2800 4450);
FORCEPROP 1 LAST COMMENT_BODY TRUE
J 0
(-3150 4475);
DISPLAY 0.872340 (-3150 4475);
PAINT GREEN (-3150 4475);
DISPLAY INVISIBLE (-3150 4475);
FORCEPROP 2 LAST PATH I73
J 0
(-2925 4625);
DISPLAY 0.680851 (-2925 4625);
DISPLAY INVISIBLE (-2925 4625);
FORCEADD OFFPAGE..4
(-3125 5025);
FORCEPROP 2 LAST $XR0 208 
J 0
(-2939 5025);
DISPLAY 0.638298 (-2939 5025);
PAINT MONO (-2939 5025);
FORCEPROP 2 LAST CDS_LIB standard
J 0
(-3125 5025);
DISPLAY INVISIBLE (-3125 5025);
FORCEPROP 1 LAST OFFPAGE TRUE
J 0
(-2800 4900);
DISPLAY 0.872340 (-2800 4900);
PAINT GREEN (-2800 4900);
DISPLAY INVISIBLE (-2800 4900);
FORCEPROP 1 LAST COMMENT_BODY TRUE
J 0
(-3150 4925);
DISPLAY 0.872340 (-3150 4925);
PAINT GREEN (-3150 4925);
DISPLAY INVISIBLE (-3150 4925);
FORCEPROP 2 LAST PATH I74
J 0
(-2925 5075);
DISPLAY 0.680851 (-2925 5075);
DISPLAY INVISIBLE (-2925 5075);
FORCEADD OFFPAGE..2
(-3125 5125);
FORCEPROP 2 LAST $XR0 208 
J 0
(-2936 5125);
DISPLAY 0.638298 (-2936 5125);
PAINT MONO (-2936 5125);
FORCEPROP 2 LAST CDS_LIB standard
J 0
(-3125 5125);
DISPLAY INVISIBLE (-3125 5125);
FORCEPROP 1 LAST OFFPAGE TRUE
J 0
(-2800 5000);
DISPLAY 0.872340 (-2800 5000);
PAINT GREEN (-2800 5000);
DISPLAY INVISIBLE (-2800 5000);
FORCEPROP 1 LAST COMMENT_BODY TRUE
J 0
(-3170 5030);
DISPLAY 0.872340 (-3170 5030);
PAINT GREEN (-3170 5030);
DISPLAY INVISIBLE (-3170 5030);
FORCEPROP 2 LAST PATH I75
J 0
(-2925 5175);
DISPLAY 0.680851 (-2925 5175);
DISPLAY INVISIBLE (-2925 5175);
FORCEADD UNIVERSAL_GND..1
(-3425 5450);
FORCEPROP 3 LASTPIN (-3425 5500) SIG_NAME GND\g
J 0
(-3415 5510);
DISPLAY 0.659574 (-3415 5510);
PAINT MONO (-3415 5510);
DISPLAY INVISIBLE (-3415 5510);
FORCEPROP 2 LAST CDS_LIB pure_quanta_power
J 0
(-3425 5450);
DISPLAY INVISIBLE (-3425 5450);
FORCEPROP 1 LAST HDL_POWER GND
J 1
(-3400 5375);
DISPLAY 0.872340 (-3400 5375);
PAINT GREEN (-3400 5375);
DISPLAY INVISIBLE (-3400 5375);
FORCEPROP 1 LAST PATH I76
J 0
(-3350 5450);
DISPLAY 0.872340 (-3350 5450);
PAINT AQUA (-3350 5450);
DISPLAY INVISIBLE (-3350 5450);
FORCEADD Q_CAP..1
(-3425 5650);
FORCEPROP 1 LAST LOCATION PC9
J 0
(-3375 5750);
DISPLAY 0.489362 (-3375 5750);
PAINT SKYBLUE (-3375 5750);
FORCEPROP 0 LAST $SEC 1
J 0
(-3375 5775);
DISPLAY 0.680851 (-3375 5775);
PAINT MONO (-3375 5775);
DISPLAY INVISIBLE (-3375 5775);
FORCEPROP 0 LAST CDS_SEC 1
J 0
(-3375 5775);
DISPLAY 1.021277 (-3375 5775);
DISPLAY INVISIBLE (-3375 5775);
FORCEPROP 1 LASTPIN (-3425 5750) $PN 1
J 0
(-3415 5730);
DISPLAY 0.489362 (-3415 5730);
PAINT MONO (-3415 5730);
FORCEPROP 1 LASTPIN (-3425 5550) $PN 2
J 0
(-3415 5530);
DISPLAY 0.489362 (-3415 5530);
PAINT MONO (-3415 5530);
FORCEPROP 1 LAST PACK_TYPE 0402
J 0
(-3375 5450);
DISPLAY 0.489362 (-3375 5450);
PAINT SKYBLUE (-3375 5450);
FORCEPROP 1 LAST VOLTAGE 25V
J 0
(-3375 5650);
DISPLAY 0.489362 (-3375 5650);
PAINT SKYBLUE (-3375 5650);
FORCEPROP 1 LAST VALUE 0.1UF
J 0
(-3375 5700);
DISPLAY 0.489362 (-3375 5700);
PAINT SKYBLUE (-3375 5700);
FORCEPROP 1 LAST TOLERANCE 10%
J 0
(-3375 5600);
DISPLAY 0.489362 (-3375 5600);
PAINT SKYBLUE (-3375 5600);
FORCEPROP 1 LAST MATERIAL X7R
J 0
(-3375 5550);
DISPLAY 0.489362 (-3375 5550);
PAINT SKYBLUE (-3375 5550);
FORCEPROP 2 LAST CDS_LIB pure_quanta
J 0
(-3425 5650);
DISPLAY INVISIBLE (-3425 5650);
FORCEPROP 1 LAST PATH I77
J 0
(-3375 5800);
DISPLAY 0.978723 (-3375 5800);
PAINT WHITE (-3375 5800);
DISPLAY INVISIBLE (-3375 5800);
FORCEPROP 1 LAST PART_NUMBER CH4104K1B00
J 0
(-3375 5500);
DISPLAY 0.489362 (-3375 5500);
PAINT SKYBLUE (-3375 5500);
DISPLAY INVISIBLE (-3375 5500);
FORCEADD UNIVERSAL_GND..1
(-3425 5900);
FORCEPROP 3 LASTPIN (-3425 5950) SIG_NAME GND\g
J 0
(-3415 5960);
DISPLAY 0.659574 (-3415 5960);
PAINT MONO (-3415 5960);
DISPLAY INVISIBLE (-3415 5960);
FORCEPROP 2 LAST CDS_LIB pure_quanta_power
J 0
(-3425 5900);
DISPLAY INVISIBLE (-3425 5900);
FORCEPROP 1 LAST HDL_POWER GND
J 1
(-3400 5825);
DISPLAY 0.872340 (-3400 5825);
PAINT GREEN (-3400 5825);
DISPLAY INVISIBLE (-3400 5825);
FORCEPROP 1 LAST PATH I78
J 0
(-3350 5900);
DISPLAY 0.872340 (-3350 5900);
PAINT AQUA (-3350 5900);
DISPLAY INVISIBLE (-3350 5900);
FORCEADD Q_CAP..1
(-3425 6150);
FORCEPROP 1 LAST LOCATION PC4
J 0
(-3375 6250);
DISPLAY 0.489362 (-3375 6250);
PAINT SKYBLUE (-3375 6250);
FORCEPROP 0 LAST $SEC 1
J 0
(-3375 6275);
DISPLAY 0.680851 (-3375 6275);
PAINT MONO (-3375 6275);
DISPLAY INVISIBLE (-3375 6275);
FORCEPROP 0 LAST CDS_SEC 1
J 0
(-3375 6275);
DISPLAY 1.021277 (-3375 6275);
DISPLAY INVISIBLE (-3375 6275);
FORCEPROP 1 LASTPIN (-3425 6250) $PN 1
J 0
(-3415 6230);
DISPLAY 0.489362 (-3415 6230);
PAINT MONO (-3415 6230);
FORCEPROP 1 LASTPIN (-3425 6050) $PN 2
J 0
(-3415 6030);
DISPLAY 0.489362 (-3415 6030);
PAINT MONO (-3415 6030);
FORCEPROP 1 LAST VOLTAGE 25V
J 0
(-3375 6150);
DISPLAY 0.489362 (-3375 6150);
PAINT SKYBLUE (-3375 6150);
FORCEPROP 1 LAST VALUE 0.1UF
J 0
(-3375 6200);
DISPLAY 0.489362 (-3375 6200);
PAINT SKYBLUE (-3375 6200);
FORCEPROP 1 LAST TOLERANCE 10%
J 0
(-3375 6100);
DISPLAY 0.489362 (-3375 6100);
PAINT SKYBLUE (-3375 6100);
FORCEPROP 1 LAST MATERIAL X7R
J 0
(-3375 6050);
DISPLAY 0.489362 (-3375 6050);
PAINT SKYBLUE (-3375 6050);
FORCEPROP 1 LAST PACK_TYPE 0402
J 0
(-3375 5950);
DISPLAY 0.489362 (-3375 5950);
PAINT SKYBLUE (-3375 5950);
FORCEPROP 2 LAST CDS_LIB pure_quanta
J 0
(-3425 6150);
DISPLAY INVISIBLE (-3425 6150);
FORCEPROP 1 LAST PATH I79
J 0
(-3375 6300);
DISPLAY 0.978723 (-3375 6300);
PAINT WHITE (-3375 6300);
DISPLAY INVISIBLE (-3375 6300);
FORCEPROP 1 LAST PART_NUMBER CH4104K1B00
J 0
(-3375 6000);
DISPLAY 0.489362 (-3375 6000);
PAINT SKYBLUE (-3375 6000);
DISPLAY INVISIBLE (-3375 6000);
FORCEADD VCC_CORE..1
(-6625 1850);
FORCEPROP 3 LASTPIN (-6625 1800) SIG_NAME P3V3_AUX\g
J 0
(-6615 1810);
DISPLAY 0.659574 (-6615 1810);
PAINT MONO (-6615 1810);
DISPLAY INVISIBLE (-6615 1810);
FORCEPROP 1 LAST HDL_POWER P3V3_AUX
J 1
(-6625 1900);
DISPLAY 0.489362 (-6625 1900);
PAINT GREEN (-6625 1900);
FORCEPROP 2 LAST CDS_LIB pure_quanta_power
J 0
(-6625 1850);
DISPLAY INVISIBLE (-6625 1850);
FORCEPROP 1 LAST PATH I8
J 0
(-6575 1875);
DISPLAY 0.872340 (-6575 1875);
PAINT AQUA (-6575 1875);
DISPLAY INVISIBLE (-6575 1875);
FORCEADD Q_CAP..1
(-3025 5675);
FORCEPROP 1 LAST LOCATION PC199
J 0
(-2975 5775);
DISPLAY 0.489362 (-2975 5775);
PAINT SKYBLUE (-2975 5775);
FORCEPROP 0 LAST $SEC 1
J 0
(-2975 5800);
DISPLAY 0.680851 (-2975 5800);
PAINT MONO (-2975 5800);
DISPLAY INVISIBLE (-2975 5800);
FORCEPROP 0 LAST CDS_SEC 1
J 0
(-2975 5800);
DISPLAY 1.021277 (-2975 5800);
DISPLAY INVISIBLE (-2975 5800);
FORCEPROP 1 LASTPIN (-3025 5775) $PN 1
J 0
(-3015 5755);
DISPLAY 0.489362 (-3015 5755);
PAINT MONO (-3015 5755);
FORCEPROP 1 LASTPIN (-3025 5575) $PN 2
J 0
(-3015 5555);
DISPLAY 0.489362 (-3015 5555);
PAINT MONO (-3015 5555);
FORCEPROP 1 LAST TOLERANCE 20%
J 0
(-2975 5625);
DISPLAY 0.489362 (-2975 5625);
PAINT SKYBLUE (-2975 5625);
FORCEPROP 1 LAST MATERIAL X6S
J 0
(-2975 5575);
DISPLAY 0.489362 (-2975 5575);
PAINT SKYBLUE (-2975 5575);
FORCEPROP 1 LAST VALUE 10UF
J 0
(-2975 5725);
DISPLAY 0.489362 (-2975 5725);
PAINT SKYBLUE (-2975 5725);
FORCEPROP 1 LAST VOLTAGE 6.3V
J 0
(-2975 5675);
DISPLAY 0.489362 (-2975 5675);
PAINT SKYBLUE (-2975 5675);
FORCEPROP 1 LAST PACK_TYPE C0402
J 0
(-2975 5475);
DISPLAY 0.489362 (-2975 5475);
PAINT SKYBLUE (-2975 5475);
FORCEPROP 2 LAST CDS_LIB pure_quanta
J 0
(-3025 5675);
DISPLAY INVISIBLE (-3025 5675);
FORCEPROP 1 LAST PATH I80
J 0
(-2975 5825);
DISPLAY 0.978723 (-2975 5825);
PAINT WHITE (-2975 5825);
DISPLAY INVISIBLE (-2975 5825);
FORCEPROP 1 LAST PART_NUMBER CH6101MEB03
J 0
(-2975 5525);
DISPLAY 0.489362 (-2975 5525);
PAINT SKYBLUE (-2975 5525);
DISPLAY INVISIBLE (-2975 5525);
FORCEADD UNIVERSAL_GND..1
(-3025 5450);
FORCEPROP 3 LASTPIN (-3025 5500) SIG_NAME GND\g
J 0
(-3015 5510);
DISPLAY 0.659574 (-3015 5510);
PAINT MONO (-3015 5510);
DISPLAY INVISIBLE (-3015 5510);
FORCEPROP 2 LAST CDS_LIB pure_quanta_power
J 0
(-3025 5450);
DISPLAY INVISIBLE (-3025 5450);
FORCEPROP 1 LAST HDL_POWER GND
J 1
(-3000 5375);
DISPLAY 0.872340 (-3000 5375);
PAINT GREEN (-3000 5375);
DISPLAY INVISIBLE (-3000 5375);
FORCEPROP 1 LAST PATH I81
J 0
(-2950 5450);
DISPLAY 0.872340 (-2950 5450);
PAINT AQUA (-2950 5450);
DISPLAY INVISIBLE (-2950 5450);
FORCEADD Q_CAP..1
(-3025 6150);
FORCEPROP 1 LAST LOCATION PC200
J 0
(-2975 6250);
DISPLAY 0.489362 (-2975 6250);
PAINT SKYBLUE (-2975 6250);
FORCEPROP 0 LAST $SEC 1
J 0
(-2975 6275);
DISPLAY 0.680851 (-2975 6275);
PAINT MONO (-2975 6275);
DISPLAY INVISIBLE (-2975 6275);
FORCEPROP 0 LAST CDS_SEC 1
J 0
(-2975 6275);
DISPLAY 1.021277 (-2975 6275);
DISPLAY INVISIBLE (-2975 6275);
FORCEPROP 1 LASTPIN (-3025 6250) $PN 1
J 0
(-3015 6230);
DISPLAY 0.489362 (-3015 6230);
PAINT MONO (-3015 6230);
FORCEPROP 1 LASTPIN (-3025 6050) $PN 2
J 0
(-3015 6030);
DISPLAY 0.489362 (-3015 6030);
PAINT MONO (-3015 6030);
FORCEPROP 1 LAST VOLTAGE 16V
J 0
(-2975 6150);
DISPLAY 0.489362 (-2975 6150);
PAINT SKYBLUE (-2975 6150);
FORCEPROP 1 LAST VALUE 1UF
J 0
(-2975 6200);
DISPLAY 0.489362 (-2975 6200);
PAINT SKYBLUE (-2975 6200);
FORCEPROP 1 LAST TOLERANCE 10%
J 0
(-2975 6100);
DISPLAY 0.489362 (-2975 6100);
PAINT SKYBLUE (-2975 6100);
FORCEPROP 1 LAST MATERIAL X6S
J 0
(-2975 6050);
DISPLAY 0.489362 (-2975 6050);
PAINT SKYBLUE (-2975 6050);
FORCEPROP 1 LAST PACK_TYPE C0402
J 0
(-2975 5950);
DISPLAY 0.489362 (-2975 5950);
PAINT SKYBLUE (-2975 5950);
FORCEPROP 2 LAST CDS_LIB pure_quanta
J 0
(-3025 6150);
DISPLAY INVISIBLE (-3025 6150);
FORCEPROP 1 LAST PATH I82
J 0
(-2975 6300);
DISPLAY 0.978723 (-2975 6300);
PAINT WHITE (-2975 6300);
DISPLAY INVISIBLE (-2975 6300);
FORCEPROP 1 LAST PART_NUMBER CH5103KEB01
J 0
(-2975 6000);
DISPLAY 0.489362 (-2975 6000);
PAINT SKYBLUE (-2975 6000);
DISPLAY INVISIBLE (-2975 6000);
FORCEADD UNIVERSAL_GND..1
(-3025 5950);
FORCEPROP 3 LASTPIN (-3025 6000) SIG_NAME GND\g
J 0
(-3015 6010);
DISPLAY 0.659574 (-3015 6010);
PAINT MONO (-3015 6010);
DISPLAY INVISIBLE (-3015 6010);
FORCEPROP 2 LAST CDS_LIB pure_quanta_power
J 0
(-3025 5950);
DISPLAY INVISIBLE (-3025 5950);
FORCEPROP 1 LAST HDL_POWER GND
J 1
(-3000 5875);
DISPLAY 0.872340 (-3000 5875);
PAINT GREEN (-3000 5875);
DISPLAY INVISIBLE (-3000 5875);
FORCEPROP 1 LAST PATH I83
J 0
(-2950 5950);
DISPLAY 0.872340 (-2950 5950);
PAINT AQUA (-2950 5950);
DISPLAY INVISIBLE (-2950 5950);
FORCEADD OFFPAGE..5
R 2
(-2825 5825);
FORCEPROP 2 LAST $XR0 208 
J 0
(-2636 5825);
DISPLAY 0.638298 (-2636 5825);
PAINT MONO (-2636 5825);
FORCEPROP 2 LAST CDS_LIB standard
J 2
(-2825 5825);
DISPLAY INVISIBLE (-2825 5825);
FORCEPROP 1 LAST OFFPAGE TRUE
J 2
(-3150 5700);
DISPLAY 0.872340 (-3150 5700);
PAINT GREEN (-3150 5700);
DISPLAY INVISIBLE (-3150 5700);
FORCEPROP 1 LAST COMMENT_BODY TRUE
J 2
(-2925 5750);
DISPLAY 0.872340 (-2925 5750);
PAINT GREEN (-2925 5750);
DISPLAY INVISIBLE (-2925 5750);
FORCEPROP 2 LAST PATH I84
J 0
(-2625 5875);
DISPLAY 0.680851 (-2625 5875);
DISPLAY INVISIBLE (-2625 5875);
FORCEADD Q_RES..1
(-2600 6300);
FORCEPROP 1 LAST LOCATION PR130
J 0
(-2650 6350);
DISPLAY 0.489362 (-2650 6350);
PAINT SKYBLUE (-2650 6350);
FORCEPROP 0 LAST $SEC 1
J 0
(-2650 6400);
DISPLAY 0.680851 (-2650 6400);
PAINT MONO (-2650 6400);
DISPLAY INVISIBLE (-2650 6400);
FORCEPROP 0 LAST CDS_SEC 1
J 0
(-2650 6400);
DISPLAY 1.021277 (-2650 6400);
DISPLAY INVISIBLE (-2650 6400);
FORCEPROP 1 LASTPIN (-2700 6300) $PN 1
J 0
(-2688 6312);
DISPLAY 0.489362 (-2688 6312);
PAINT MONO (-2688 6312);
FORCEPROP 1 LASTPIN (-2500 6300) $PN 2
J 0
(-2538 6312);
DISPLAY 0.489362 (-2538 6312);
PAINT MONO (-2538 6312);
FORCEPROP 1 LAST VALUE 1
J 2
(-2750 6325);
DISPLAY 0.489362 (-2750 6325);
PAINT SKYBLUE (-2750 6325);
FORCEPROP 1 LAST TOLERANCE 1%
J 0
(-2475 6325);
DISPLAY 0.489362 (-2475 6325);
PAINT SKYBLUE (-2475 6325);
FORCEPROP 1 LAST PACK_TYPE 0402LF
J 0
(-2775 6225);
DISPLAY 0.489362 (-2775 6225);
PAINT SKYBLUE (-2775 6225);
FORCEPROP 1 LAST MATERIAL CHIP
J 0
(-2475 6250);
DISPLAY 0.489362 (-2475 6250);
PAINT SKYBLUE (-2475 6250);
FORCEPROP 1 LAST WATTAGE 1/16W
J 0
(-2475 6225);
DISPLAY 0.489362 (-2475 6225);
PAINT SKYBLUE (-2475 6225);
FORCEPROP 2 LAST CDS_LIB pure_quanta
J 0
(-2600 6300);
DISPLAY INVISIBLE (-2600 6300);
FORCEPROP 1 LAST PATH I85
J 0
(-2650 6450);
DISPLAY 0.978723 (-2650 6450);
PAINT WHITE (-2650 6450);
DISPLAY INVISIBLE (-2650 6450);
FORCEPROP 1 LAST PART_NUMBER CS-1002FB04
J 0
(-2775 6250);
DISPLAY 0.489362 (-2775 6250);
PAINT SKYBLUE (-2775 6250);
DISPLAY INVISIBLE (-2775 6250);
FORCEADD VCC_CORE..1
(-2225 6400);
FORCEPROP 3 LASTPIN (-2225 6350) SIG_NAME P3V3_AUX\g
J 0
(-2215 6360);
DISPLAY 0.659574 (-2215 6360);
PAINT MONO (-2215 6360);
DISPLAY INVISIBLE (-2215 6360);
FORCEPROP 1 LAST HDL_POWER P3V3_AUX
J 1
(-2225 6450);
DISPLAY 0.489362 (-2225 6450);
PAINT GREEN (-2225 6450);
FORCEPROP 2 LAST CDS_LIB pure_quanta_power
J 0
(-2225 6400);
DISPLAY INVISIBLE (-2225 6400);
FORCEPROP 1 LAST PATH I86
J 0
(-2175 6425);
DISPLAY 0.872340 (-2175 6425);
PAINT AQUA (-2175 6425);
DISPLAY INVISIBLE (-2175 6425);
FORCEADD UNIVERSAL_GND..1
(-6500 4300);
FORCEPROP 3 LASTPIN (-6500 4350) SIG_NAME GND\g
J 0
(-6490 4360);
DISPLAY 0.659574 (-6490 4360);
PAINT MONO (-6490 4360);
DISPLAY INVISIBLE (-6490 4360);
FORCEPROP 2 LAST CDS_LIB pure_quanta_power
J 0
(-6500 4300);
PAINT MONO (-6500 4300);
DISPLAY INVISIBLE (-6500 4300);
FORCEPROP 1 LAST HDL_POWER GND
J 1
(-6475 4225);
DISPLAY 0.872340 (-6475 4225);
PAINT GREEN (-6475 4225);
DISPLAY INVISIBLE (-6475 4225);
FORCEPROP 1 LAST PATH I87
J 0
(-6425 4300);
DISPLAY 0.872340 (-6425 4300);
PAINT AQUA (-6425 4300);
DISPLAY INVISIBLE (-6425 4300);
FORCEADD Q_CAP..1
(-6500 4500);
FORCEPROP 1 LAST LOCATION C5009
J 0
(-6400 4500);
DISPLAY 0.510638 (-6400 4500);
FORCEPROP 0 LAST $SEC 1
J 0
(-6250 4525);
DISPLAY 0.680851 (-6250 4525);
PAINT MONO (-6250 4525);
DISPLAY INVISIBLE (-6250 4525);
FORCEPROP 0 LAST CDS_SEC 1
J 0
(-6250 4525);
DISPLAY 0.680851 (-6250 4525);
DISPLAY INVISIBLE (-6250 4525);
FORCEPROP 1 LASTPIN (-6500 4600) $PN 1
J 0
(-6490 4580);
DISPLAY 0.787234 (-6490 4580);
PAINT MONO (-6490 4580);
FORCEPROP 1 LASTPIN (-6500 4400) $PN 2
J 0
(-6490 4380);
DISPLAY 0.787234 (-6490 4380);
PAINT MONO (-6490 4380);
FORCEPROP 1 LAST VOLTAGE 50V
J 0
(-6250 4425);
DISPLAY 0.510638 (-6250 4425);
FORCEPROP 1 LAST TOLERANCE 5%
J 0
(-6250 4400);
DISPLAY 0.510638 (-6250 4400);
FORCEPROP 1 LAST PACK_TYPE 0402
J 0
(-6250 4475);
DISPLAY 0.510638 (-6250 4475);
FORCEPROP 1 LAST VALUE 1000PF
J 0
(-6425 4475);
DISPLAY 0.510638 (-6425 4475);
FORCEPROP 1 LAST MATERIAL X7R
J 0
(-6250 4450);
DISPLAY 0.510638 (-6250 4450);
FORCEPROP 2 LAST CDS_LIB pure_quanta
J 0
(-6500 4500);
DISPLAY INVISIBLE (-6500 4500);
FORCEPROP 1 LAST PATH I88
J 0
(-6450 4650);
DISPLAY 0.978723 (-6450 4650);
PAINT WHITE (-6450 4650);
DISPLAY INVISIBLE (-6450 4650);
FORCEPROP 1 LAST PART_NUMBER TMP_QCH21006JB10
J 0
(-6250 4500);
DISPLAY 0.510638 (-6250 4500);
DISPLAY INVISIBLE (-6250 4500);
FORCEADD Q_RES..1
(-6200 1725);
FORCEPROP 1 LAST LOCATION R8458
J 0
(-6250 1775);
DISPLAY 0.489362 (-6250 1775);
PAINT SKYBLUE (-6250 1775);
FORCEPROP 0 LAST $SEC 1
J 0
(-6250 1800);
DISPLAY 0.680851 (-6250 1800);
PAINT MONO (-6250 1800);
DISPLAY INVISIBLE (-6250 1800);
FORCEPROP 0 LAST CDS_SEC 1
J 0
(-6250 1800);
DISPLAY 1.021277 (-6250 1800);
DISPLAY INVISIBLE (-6250 1800);
FORCEPROP 1 LASTPIN (-6300 1725) $PN 1
J 0
(-6288 1737);
DISPLAY 0.489362 (-6288 1737);
PAINT MONO (-6288 1737);
FORCEPROP 1 LASTPIN (-6100 1725) $PN 2
J 0
(-6138 1737);
DISPLAY 0.489362 (-6138 1737);
PAINT MONO (-6138 1737);
FORCEPROP 1 LAST MATERIAL EMPTY
J 0
(-6450 1650);
DISPLAY 0.489362 (-6450 1650);
PAINT RED (-6450 1650);
FORCEPROP 1 LAST VALUE 0
J 2
(-6325 1750);
DISPLAY 0.489362 (-6325 1750);
PAINT SKYBLUE (-6325 1750);
FORCEPROP 1 LAST TOLERANCE 5%
J 0
(-6075 1750);
DISPLAY 0.489362 (-6075 1750);
PAINT SKYBLUE (-6075 1750);
FORCEPROP 1 LAST PACK_TYPE 0402LF
J 0
(-6100 1650);
DISPLAY 0.489362 (-6100 1650);
PAINT SKYBLUE (-6100 1650);
FORCEPROP 1 LAST WATTAGE 1/16W
J 0
(-6100 1675);
DISPLAY 0.489362 (-6100 1675);
PAINT SKYBLUE (-6100 1675);
FORCEPROP 2 LAST CDS_LIB pure_quanta
J 0
(-6200 1725);
DISPLAY INVISIBLE (-6200 1725);
FORCEPROP 1 LAST PATH I9
J 0
(-6250 1875);
DISPLAY 0.978723 (-6250 1875);
PAINT WHITE (-6250 1875);
DISPLAY INVISIBLE (-6250 1875);
FORCEPROP 1 LAST PART_NUMBER CS00002JB13
J 0
(-6450 1675);
DISPLAY 0.489362 (-6450 1675);
PAINT SKYBLUE (-6450 1675);
DISPLAY INVISIBLE (-6450 1675);
FORCEADD DNS..1
(-1700 1600);
PAINT RED (-1700 1600);
FORCEPROP 2 LAST CDS_LIB mstr_misc
J 0
(-1700 1600);
DISPLAY INVISIBLE (-1700 1600);
FORCEPROP 1 LAST COMMENT_BODY TRUE
R 1
J 0
(-1625 1375);
DISPLAY 0.872340 (-1625 1375);
PAINT GREEN (-1625 1375);
DISPLAY INVISIBLE (-1625 1375);
FORCEADD DNS..1
(-6250 1725);
PAINT RED (-6250 1725);
FORCEPROP 2 LAST CDS_LIB mstr_misc
J 0
(-6250 1725);
DISPLAY INVISIBLE (-6250 1725);
FORCEPROP 1 LAST COMMENT_BODY TRUE
R 1
J 0
(-6175 1500);
DISPLAY 0.872340 (-6175 1500);
PAINT GREEN (-6175 1500);
DISPLAY INVISIBLE (-6175 1500);
FORCEADD DNS..1
(-5350 6375);
PAINT RED (-5350 6375);
FORCEPROP 2 LAST CDS_LIB mstr_misc
J 0
(-5350 6375);
DISPLAY INVISIBLE (-5350 6375);
FORCEPROP 1 LAST COMMENT_BODY TRUE
R 1
J 0
(-5275 6150);
DISPLAY 0.872340 (-5275 6150);
PAINT GREEN (-5275 6150);
DISPLAY INVISIBLE (-5275 6150);
FORCEADD DNS..1
(-6000 2325);
PAINT RED (-6000 2325);
FORCEPROP 2 LAST CDS_LIB mstr_misc
J 0
(-6000 2325);
DISPLAY INVISIBLE (-6000 2325);
FORCEPROP 1 LAST COMMENT_BODY TRUE
R 1
J 0
(-5925 2100);
DISPLAY 0.872340 (-5925 2100);
PAINT GREEN (-5925 2100);
DISPLAY INVISIBLE (-5925 2100);
FORCEADD DNS..1
(-5700 475);
PAINT RED (-5700 475);
FORCEPROP 2 LAST CDS_LIB mstr_misc
J 0
(-5700 475);
DISPLAY INVISIBLE (-5700 475);
FORCEPROP 1 LAST COMMENT_BODY TRUE
R 1
J 0
(-5625 250);
DISPLAY 0.872340 (-5625 250);
PAINT GREEN (-5625 250);
DISPLAY INVISIBLE (-5625 250);
FORCEADD QUANTA_TITLE_BLOCK_C..1
(0 0);
FORCEPROP 0 LAST CDS_CON_LAST_MODIFIED Thu Sep 14 16:12:19 2023
J 0
(-1885 15);
DISPLAY INVISIBLE (-1885 15);
FORCEPROP 1 LAST CUSTOM_TXT_CDS <CON_LAST_MODIFIED>
J 0
(-1885 15);
DISPLAY 0.978723 (-1885 15);
FORCEPROP 2 LAST CUSTOM_TXT_CDS <XR_PAGE_TITLE>
J 0
(-7890 5250);
DISPLAY 0.638298 (-7890 5250);
PAINT PINK (-7890 5250);
DISPLAY INVISIBLE (-7890 5250);
FORCEPROP 1 LAST CUSTOM_TXT_CDS <NAME_2>
J 0
(-3175 50);
FORCEPROP 1 LAST CUSTOM_TXT_CDS <NAME_1>
J 0
(-3175 175);
FORCEPROP 1 LAST CUSTOM_TXT_CDS <Q_NUMBER>
J 0
(-1403 103);
DISPLAY 1.212766 (-1403 103);
FORCEPROP 1 LAST CUSTOM_TXT_CDS <Q_PROJ>
J 0
(-2382 102);
DISPLAY 1.212766 (-2382 102);
FORCEPROP 1 LAST CUSTOM_TXT_CDS <Q_REV>
J 0
(-184 103);
DISPLAY 1.212766 (-184 103);
FORCEPROP 1 LAST CUSTOM_TXT_CDS <CON_PAGE_NUM> OF <CON_TOTAL_PAGES>
J 0
(-446 18);
DISPLAY 0.978723 (-446 18);
FORCEPROP 1 LAST Q_TITLE PVDD11_S3_P0 VR CONTROLLER
J 0
(-9325 50);
DISPLAY 2.446809 (-9325 50);
PAINT GREEN (-9325 50);
FORCEPROP 2 LAST CDS_XR_PAGE_TITLE CR-207 : @T6G_MB_LIB.T6G(SCH_1):PAGE207
J 0
(-7890 5250);
DISPLAY 0.638298 (-7890 5250);
PAINT PINK (-7890 5250);
DISPLAY INVISIBLE (-7890 5250);
FORCEPROP 2 LAST PAGE_BORDER TRUE
J 0
(-7890 5250);
DISPLAY 0.638298 (-7890 5250);
PAINT PINK (-7890 5250);
DISPLAY INVISIBLE (-7890 5250);
FORCEPROP 2 LAST CDS_LIB pure_quanta
J 0
(0 0);
DISPLAY INVISIBLE (0 0);
FORCEPROP 1 LAST CDS_LMAN_SYM_OUTLINE -9475,6775,100,-125
J 0
(0 0);
DISPLAY 0.468085 (0 0);
PAINT GREEN (0 0);
DISPLAY INVISIBLE (0 0);
FORCEPROP 1 LAST Q_DEPT BU9
J 1
(-3763 49);
DISPLAY 1.957447 (-3763 49);
PAINT GREEN (-3763 49);
DISPLAY INVISIBLE (-3763 49);
FORCEPROP 1 LAST COMMENT_BODY TRUE
J 0
(12 -13);
DISPLAY 0.978723 (12 -13);
PAINT GREEN (12 -13);
DISPLAY INVISIBLE (12 -13);
FORCEADD DNS..1
(-2175 1400);
PAINT RED (-2175 1400);
FORCEPROP 2 LAST CDS_LIB mstr_misc
J 0
(-2175 1400);
DISPLAY INVISIBLE (-2175 1400);
FORCEPROP 1 LAST COMMENT_BODY TRUE
R 1
J 0
(-2100 1175);
DISPLAY 0.872340 (-2100 1175);
PAINT GREEN (-2100 1175);
DISPLAY INVISIBLE (-2100 1175);
FORCEADD DNS..1
(-1750 1825);
PAINT RED (-1750 1825);
FORCEPROP 2 LAST CDS_LIB mstr_misc
J 0
(-1750 1825);
DISPLAY INVISIBLE (-1750 1825);
FORCEPROP 1 LAST COMMENT_BODY TRUE
R 1
J 0
(-1675 1600);
DISPLAY 0.872340 (-1675 1600);
PAINT GREEN (-1675 1600);
DISPLAY INVISIBLE (-1675 1600);
FORCEADD DNS..1
(-6275 2100);
PAINT RED (-6275 2100);
FORCEPROP 2 LAST CDS_LIB mstr_misc
J 0
(-6275 2100);
DISPLAY INVISIBLE (-6275 2100);
FORCEPROP 1 LAST COMMENT_BODY TRUE
R 1
J 0
(-6200 1875);
DISPLAY 0.872340 (-6200 1875);
PAINT GREEN (-6200 1875);
DISPLAY INVISIBLE (-6200 1875);
WIRE 16 -1 (-6900 3575)(-6900 3550);
WIRE 16 -1 (-5725 375)(-5725 325);
WIRE 16 -1 (-5400 400)(-5400 325);
WIRE 16 -1 (-5700 1125)(-5700 1175);
WIRE 16 -1 (-6000 2450)(-6000 2500);
WIRE 16 -1 (-6975 575)(-6975 450);
WIRE 16 -1 (-6900 4350)(-6900 4400);
WIRE 16 -1 (-3475 625)(-3475 500);
WIRE 16 -1 (-6550 575)(-6550 450);
WIRE 16 -1 (-3050 1225)(-2700 1225);
WIRE 16 -1 (-2700 1225)(-2700 1200);
WIRE 16 -1 (-3050 1875)(-2700 1875);
WIRE 16 -1 (-2700 1875)(-2700 1850);
WIRE 16 -1 (-2175 1325)(-2175 1250);
WIRE 16 -1 (-3050 2325)(-2700 2325);
WIRE 16 -1 (-2700 2325)(-2700 2300);
WIRE 16 -1 (-3050 2775)(-2700 2775);
WIRE 16 -1 (-2700 2775)(-2700 2750);
WIRE 16 -1 (-3050 3225)(-2700 3225);
WIRE 16 -1 (-2700 3225)(-2700 3200);
WIRE 16 -1 (-3050 3675)(-2700 3675);
WIRE 16 -1 (-2700 3675)(-2700 3650);
WIRE 16 -1 (-3025 4125)(-2700 4125);
WIRE 16 -1 (-2700 4125)(-2700 4100);
WIRE 16 -1 (-3425 5550)(-3425 5500);
WIRE 16 -1 (-3425 6050)(-3425 5950);
WIRE 16 -1 (-3025 5500)(-3025 5575);
WIRE 16 -1 (-3025 6000)(-3025 6050);
WIRE 16 -1 (-6500 4400)(-6500 4350);
WIRE 16 -1 (-6975 850)(-6550 850);
WIRE 16 -1 (-6975 775)(-6975 850);
WIRE 16 -1 (-7200 850)(-6975 850);
WIRE 16 -1 (-5700 850)(-6550 850);
WIRE 16 -1 (-6550 775)(-6550 850);
WIRE 16 -1 (-5700 850)(-5700 775);
WIRE 16 -1 (-5700 775)(-5125 775);
FORCEPROP 2 LAST SIG_NAME PVDD11_S3_P0_VMON
J 2
(-5260 785);
DISPLAY 0.489362 (-5260 785);
FORCEPROP 2 LASTPROP $XRERR UNIQUE?
J 0
(-5500 785);
DISPLAY 0.638298 (-5500 785);
PAINT MONO (-5500 785);
DISPLAY INVISIBLE (-5500 785);
WIRE 16 -1 (-5775 3825)(-5125 3825);
WIRE 16 -1 (-5775 3850)(-5775 3825);
WIRE 16 -1 (-5775 3825)(-6900 3825);
WIRE 16 -1 (-6900 3775)(-6900 3825);
WIRE 16 -1 (-7525 3825)(-6900 3825);
FORCEPROP 2 LAST SIG_NAME VSENSE_VSS_SENSE_C_P0
J 2
(-6935 3835);
DISPLAY 0.489362 (-6935 3835);
WIRE 16 -1 (-6175 4075)(-6900 4075);
WIRE 16 -1 (-6900 4150)(-6900 4075);
WIRE 16 -1 (-7525 4075)(-6900 4075);
FORCEPROP 2 LAST SIG_NAME VSENSE_PVDD11_S3_P0_DP
J 2
(-6935 4085);
DISPLAY 0.489362 (-6935 4085);
WIRE 17 273 (-7825 4225)(-7500 4225);
WIRE 17 273 (-7825 3675)(-7825 4225);
WIRE 17 273 (-7500 4225)(-7500 3675);
WIRE 17 273 (-7825 3675)(-7500 3675);
WIRE 16 -1 (-3775 4225)(-2950 4225);
FORCEPROP 2 LAST SIG_NAME NC_PVDD11_S3_P0_PWM3
J 2
(-3210 4235);
DISPLAY 0.489362 (-3210 4235);
FORCEPROP 2 LASTPROP $XRERR UNIQUE?
J 0
(-2920 4225);
DISPLAY 0.638298 (-2920 4225);
PAINT MONO (-2920 4225);
DISPLAY INVISIBLE (-2920 4225);
WIRE 17 273 (-9175 225)(-7950 225);
WIRE 17 273 (-9175 650)(-9175 225);
WIRE 17 273 (-7950 650)(-7950 225);
WIRE 17 273 (-9175 650)(-7950 650);
WIRE 16 -1 (-2225 6350)(-2225 6300);
WIRE 16 -1 (-2225 6300)(-2500 6300);
WIRE 16 -1 (-6625 1725)(-6300 1725);
WIRE 16 -1 (-6625 1800)(-6625 1725);
WIRE 16 -1 (-6150 675)(-6275 675);
WIRE 16 -1 (-6275 700)(-6275 675);
WIRE 16 -1 (-1400 1950)(-1400 1850);
WIRE 16 -1 (-1400 1850)(-1650 1850);
WIRE 16 -1 (-5100 6375)(-5100 6400);
WIRE 16 -1 (-5100 6400)(-5250 6400);
WIRE 16 -1 (-5100 5825)(-5100 5850);
WIRE 16 -1 (-5100 5850)(-5225 5850);
WIRE 16 -1 (-5125 5675)(-6075 5675);
WIRE 16 -1 (-6075 5675)(-6075 5525);
WIRE 16 -1 (-6075 5525)(-5125 5525);
WIRE 16 -1 (-6075 5525)(-6075 5225);
WIRE 16 -1 (-6075 5225)(-5125 5225);
WIRE 16 -1 (-6075 5175)(-6075 5225);
WIRE 16 -1 (-6625 6400)(-6325 6400);
WIRE 16 -1 (-6625 6475)(-6625 6400);
WIRE 16 -1 (-5400 2725)(-5125 2725);
WIRE 16 -1 (-5400 2975)(-5400 2725);
WIRE 16 -1 (-5400 2625)(-5400 2725);
WIRE 16 -1 (-5125 2975)(-5400 2975);
WIRE 16 -1 (-5200 575)(-5125 575);
WIRE 16 -1 (-5200 525)(-5200 575);
WIRE 16 -1 (-7650 850)(-7400 850);
WIRE 16 -1 (-7650 900)(-7650 850);
WIRE 16 -1 (-5700 1425)(-5125 1425);
FORCEPROP 2 LAST SIG_NAME PVDD11_S3_P0_ADDR_CFG
J 2
(-5235 1435);
DISPLAY 0.489362 (-5235 1435);
FORCEPROP 2 LASTPROP $XRERR UNIQUE?
J 0
(-5475 1435);
DISPLAY 0.638298 (-5475 1435);
PAINT MONO (-5475 1435);
DISPLAY INVISIBLE (-5475 1435);
WIRE 16 -1 (-5700 1425)(-5700 1375);
WIRE 16 -1 (-3250 3225)(-3775 3225);
FORCEPROP 2 LAST SIG_NAME NC_PVDD11_S3_P0_IMON5
J 2
(-3235 3235);
DISPLAY 0.489362 (-3235 3235);
FORCEPROP 2 LASTPROP $XRERR UNIQUE?
J 0
(-3475 3235);
DISPLAY 0.638298 (-3475 3235);
PAINT MONO (-3475 3235);
DISPLAY INVISIBLE (-3475 3235);
WIRE 16 -1 (-3775 3325)(-2950 3325);
FORCEPROP 2 LAST SIG_NAME NC_PVDD11_S3_P0_PWM5
J 2
(-3210 3335);
DISPLAY 0.489362 (-3210 3335);
FORCEPROP 2 LASTPROP $XRERR UNIQUE?
J 0
(-2920 3325);
DISPLAY 0.638298 (-2920 3325);
PAINT MONO (-2920 3325);
DISPLAY INVISIBLE (-2920 3325);
WIRE 17 273 (-1800 6600)(-200 6600);
WIRE 17 273 (-1800 6600)(-1800 5700);
WIRE 17 273 (-200 6600)(-200 5700);
WIRE 17 273 (-1800 5700)(-200 5700);
WIRE 16 -1 (-3775 5025)(-3175 5025);
FORCEPROP 2 LAST SIG_NAME PVDD11_S3_P0_IMON1
J 2
(-3285 5035);
DISPLAY 0.489362 (-3285 5035);
WIRE 16 -1 (-3775 6125)(-3550 6125);
WIRE 16 -1 (-3550 6125)(-3550 6300);
WIRE 16 -1 (-3550 6300)(-3425 6300);
WIRE 16 -1 (-3425 6300)(-3025 6300);
FORCEPROP 2 LAST SIG_NAME PVDD11_S3_P0_VCC
J 2
(-3110 6325);
DISPLAY 0.489362 (-3110 6325);
FORCEPROP 2 LASTPROP $XRERR UNIQUE?
J 0
(-3350 6325);
DISPLAY 0.638298 (-3350 6325);
PAINT MONO (-3350 6325);
DISPLAY INVISIBLE (-3350 6325);
WIRE 16 -1 (-3425 6300)(-3425 6250);
WIRE 16 -1 (-2700 6300)(-3025 6300);
WIRE 16 -1 (-3025 6250)(-3025 6300);
WIRE 16 -1 (-5125 4975)(-5975 4975);
FORCEPROP 2 LAST SIG_NAME PVDD11_S3_P0_PMSCL_R
J 2
(-5260 4985);
DISPLAY 0.489362 (-5260 4985);
FORCEPROP 2 LASTPROP $XRERR UNIQUE?
J 0
(-5500 4985);
DISPLAY 0.638298 (-5500 4985);
PAINT MONO (-5500 4985);
DISPLAY INVISIBLE (-5500 4985);
WIRE 16 -1 (-3775 4575)(-3175 4575);
FORCEPROP 2 LAST SIG_NAME PVDD11_S3_P0_IMON2
J 2
(-3285 4585);
DISPLAY 0.489362 (-3285 4585);
WIRE 16 -1 (-5125 5375)(-5825 5375);
FORCEPROP 2 LAST SIG_NAME NC_PVDD11_S3_P0_SVTO
J 2
(-5310 5385);
DISPLAY 0.489362 (-5310 5385);
FORCEPROP 2 LASTPROP $XRERR UNIQUE?
J 0
(-6065 5375);
DISPLAY 0.638298 (-6065 5375);
PAINT MONO (-6065 5375);
DISPLAY INVISIBLE (-6065 5375);
WIRE 16 -1 (-2075 1850)(-1850 1850);
WIRE 16 -1 (-2075 1625)(-2075 1850);
WIRE 16 -1 (-2075 1625)(-1800 1625);
WIRE 16 -1 (-2175 1625)(-2075 1625);
WIRE 16 -1 (-2175 1625)(-2175 1525);
WIRE 16 -1 (-3775 1625)(-2175 1625);
FORCEPROP 2 LAST SIG_NAME PVDD11_S3_P0_RESET_N_R
J 2
(-2135 1635);
DISPLAY 0.489362 (-2135 1635);
FORCEPROP 2 LASTPROP $XRERR UNIQUE?
J 0
(-2375 1635);
DISPLAY 0.638298 (-2375 1635);
PAINT MONO (-2375 1635);
DISPLAY INVISIBLE (-2375 1635);
WIRE 16 -1 (-3225 4125)(-3775 4125);
FORCEPROP 2 LAST SIG_NAME NC_PVDD11_S3_P0_IMON3
J 2
(-3210 4135);
DISPLAY 0.489362 (-3210 4135);
FORCEPROP 2 LASTPROP $XRERR UNIQUE?
J 0
(-3450 4135);
DISPLAY 0.638298 (-3450 4135);
PAINT MONO (-3450 4135);
DISPLAY INVISIBLE (-3450 4135);
WIRE 16 -1 (-3250 3675)(-3775 3675);
FORCEPROP 2 LAST SIG_NAME NC_PVDD11_S3_P0_IMON4
J 2
(-3235 3685);
DISPLAY 0.489362 (-3235 3685);
FORCEPROP 2 LASTPROP $XRERR UNIQUE?
J 0
(-3475 3685);
DISPLAY 0.638298 (-3475 3685);
PAINT MONO (-3475 3685);
DISPLAY INVISIBLE (-3475 3685);
WIRE 16 -1 (-5125 875)(-5650 875);
FORCEPROP 2 LAST SIG_NAME NC_PVDD11_S3_P0_PG1
J 0
(-5660 885);
DISPLAY 0.489362 (-5660 885);
FORCEPROP 2 LASTPROP $XRERR UNIQUE?
J 0
(-5890 875);
DISPLAY 0.638298 (-5890 875);
PAINT MONO (-5890 875);
DISPLAY INVISIBLE (-5890 875);
WIRE 16 -1 (-5975 4675)(-5125 4675);
FORCEPROP 2 LAST SIG_NAME PVDD11_S3_P0_PMALERT_R
J 2
(-5210 4685);
DISPLAY 0.489362 (-5210 4685);
FORCEPROP 2 LASTPROP $XRERR UNIQUE?
J 0
(-5450 4685);
DISPLAY 0.638298 (-5450 4685);
PAINT MONO (-5450 4685);
DISPLAY INVISIBLE (-5450 4685);
WIRE 16 -1 (-5425 5850)(-5725 5850);
WIRE 16 -1 (-5725 5850)(-5725 5975);
WIRE 16 -1 (-5725 5975)(-5125 5975);
FORCEPROP 2 LAST SIG_NAME PVDD11_S3_P0_EN_R
J 2
(-5235 5985);
DISPLAY 0.489362 (-5235 5985);
FORCEPROP 2 LASTPROP $XRERR UNIQUE?
J 0
(-5475 5985);
DISPLAY 0.638298 (-5475 5985);
PAINT MONO (-5475 5985);
DISPLAY INVISIBLE (-5475 5985);
WIRE 16 -1 (-5900 5975)(-5725 5975);
WIRE 16 -1 (-5125 4825)(-5975 4825);
FORCEPROP 2 LAST SIG_NAME PVDD11_S3_P0_PMSDA_R
J 2
(-5260 4835);
DISPLAY 0.489362 (-5260 4835);
FORCEPROP 2 LASTPROP $XRERR UNIQUE?
J 0
(-5500 4835);
DISPLAY 0.638298 (-5500 4835);
PAINT MONO (-5500 4835);
DISPLAY INVISIBLE (-5500 4835);
WIRE 16 -1 (-3775 3775)(-2950 3775);
FORCEPROP 2 LAST SIG_NAME NC_PVDD11_S3_P0_PWM4
J 2
(-3210 3785);
DISPLAY 0.489362 (-3210 3785);
FORCEPROP 2 LASTPROP $XRERR UNIQUE?
J 0
(-2920 3775);
DISPLAY 0.638298 (-2920 3775);
PAINT MONO (-2920 3775);
DISPLAY INVISIBLE (-2920 3775);
WIRE 16 -1 (-5975 4075)(-5775 4075);
WIRE 16 -1 (-5775 4075)(-5125 4075);
FORCEPROP 2 LAST SIG_NAME VSENSE_PVDD11_S3_P0_R
J 2
(-5235 4085);
DISPLAY 0.489362 (-5235 4085);
FORCEPROP 2 LASTPROP $XRERR UNIQUE?
J 0
(-5475 4085);
DISPLAY 0.638298 (-5475 4085);
PAINT MONO (-5475 4085);
DISPLAY INVISIBLE (-5475 4085);
WIRE 16 -1 (-5775 4050)(-5775 4075);
WIRE 16 -1 (-3775 2425)(-2950 2425);
FORCEPROP 2 LAST SIG_NAME NC_PVDD11_S3_P0_PWM7
J 2
(-3210 2435);
DISPLAY 0.489362 (-3210 2435);
FORCEPROP 2 LASTPROP $XRERR UNIQUE?
J 0
(-2920 2425);
DISPLAY 0.638298 (-2920 2425);
PAINT MONO (-2920 2425);
DISPLAY INVISIBLE (-2920 2425);
WIRE 16 -1 (-5725 6400)(-5450 6400);
WIRE 16 -1 (-6125 6400)(-5725 6400);
WIRE 16 -1 (-5725 6400)(-5725 6125);
WIRE 16 -1 (-5725 6125)(-5125 6125);
FORCEPROP 2 LAST SIG_NAME PWRGD_PVDD11_S3_P0_R
J 2
(-5235 6135);
DISPLAY 0.489362 (-5235 6135);
FORCEPROP 2 LASTPROP $XRERR UNIQUE?
J 0
(-5475 6135);
DISPLAY 0.638298 (-5475 6135);
PAINT MONO (-5475 6135);
DISPLAY INVISIBLE (-5475 6135);
WIRE 16 -1 (-5725 6125)(-5900 6125);
WIRE 16 -1 (-3775 4675)(-3175 4675);
FORCEPROP 2 LAST SIG_NAME PVDD11_S3_P0_PWM2
J 2
(-3310 4685);
DISPLAY 0.489362 (-3310 4685);
WIRE 16 -1 (-3025 5775)(-3025 5825);
WIRE 16 -1 (-2875 5825)(-3025 5825);
WIRE 16 -1 (-3425 5825)(-3025 5825);
FORCEPROP 2 LAST SIG_NAME PVDD11_S3_P0_VCCS
J 2
(-3310 5835);
DISPLAY 0.489362 (-3310 5835);
WIRE 16 -1 (-3425 5825)(-3425 5750);
WIRE 16 -1 (-3775 5825)(-3425 5825);
WIRE 16 -1 (-5950 675)(-5725 675);
WIRE 16 -1 (-5725 675)(-5400 675);
WIRE 16 -1 (-5725 575)(-5725 675);
WIRE 16 -1 (-5125 675)(-5400 675);
FORCEPROP 2 LAST SIG_NAME PVDD11_S3_P0_VINSEN
J 2
(-5235 685);
DISPLAY 0.489362 (-5235 685);
FORCEPROP 2 LASTPROP $XRERR UNIQUE?
J 0
(-5475 685);
DISPLAY 0.638298 (-5475 685);
PAINT MONO (-5475 685);
DISPLAY INVISIBLE (-5475 685);
WIRE 16 -1 (-5400 600)(-5400 675);
WIRE 16 -1 (-3200 925)(-3475 925);
FORCEPROP 2 LAST SIG_NAME PVDD11_S3_P0_TEMP0
J 2
(-3260 935);
DISPLAY 0.489362 (-3260 935);
WIRE 16 -1 (-3475 825)(-3475 925);
WIRE 16 -1 (-3475 925)(-3775 925);
WIRE 16 -1 (-6100 1725)(-5850 1725);
WIRE 16 -1 (-5850 1725)(-5850 1875);
WIRE 16 -1 (-5125 1875)(-5850 1875);
FORCEPROP 2 LAST SIG_NAME PVDD11_S3_P0_VDDIO
J 2
(-5235 1885);
DISPLAY 0.489362 (-5235 1885);
FORCEPROP 2 LASTPROP $XRERR UNIQUE?
J 0
(-5475 1885);
DISPLAY 0.638298 (-5475 1885);
PAINT MONO (-5475 1885);
DISPLAY INVISIBLE (-5475 1885);
WIRE 16 -1 (-3250 2325)(-3775 2325);
FORCEPROP 2 LAST SIG_NAME NC_PVDD11_S3_P0_IMON7
J 2
(-3235 2335);
DISPLAY 0.489362 (-3235 2335);
FORCEPROP 2 LASTPROP $XRERR UNIQUE?
J 0
(-3475 2335);
DISPLAY 0.638298 (-3475 2335);
PAINT MONO (-3475 2335);
DISPLAY INVISIBLE (-3475 2335);
WIRE 16 -1 (-3775 5125)(-3175 5125);
FORCEPROP 2 LAST SIG_NAME PVDD11_S3_P0_PWM1
J 2
(-3310 5135);
DISPLAY 0.489362 (-3310 5135);
WIRE 16 -1 (-3775 2875)(-2950 2875);
FORCEPROP 2 LAST SIG_NAME NC_PVDD11_S3_P0_PWM6
J 2
(-3210 2885);
DISPLAY 0.489362 (-3210 2885);
FORCEPROP 2 LASTPROP $XRERR UNIQUE?
J 0
(-2920 2875);
DISPLAY 0.638298 (-2920 2875);
PAINT MONO (-2920 2875);
DISPLAY INVISIBLE (-2920 2875);
WIRE 16 -1 (-3250 2775)(-3775 2775);
FORCEPROP 2 LAST SIG_NAME NC_PVDD11_S3_P0_IMON6
J 2
(-3235 2785);
DISPLAY 0.489362 (-3235 2785);
FORCEPROP 2 LASTPROP $XRERR UNIQUE?
J 0
(-3475 2785);
DISPLAY 0.638298 (-3475 2785);
PAINT MONO (-3475 2785);
DISPLAY INVISIBLE (-3475 2785);
WIRE 16 -1 (-6175 2125)(-6000 2125);
WIRE 16 -1 (-5125 2125)(-6000 2125);
FORCEPROP 2 LAST SIG_NAME PVDD11_S3_P0_OCP_N_R
J 2
(-5235 2135);
DISPLAY 0.489362 (-5235 2135);
FORCEPROP 2 LASTPROP $XRERR UNIQUE?
J 0
(-5475 2135);
DISPLAY 0.638298 (-5475 2135);
PAINT MONO (-5475 2135);
DISPLAY INVISIBLE (-5475 2135);
WIRE 16 -1 (-6000 2250)(-6000 2125);
WIRE 16 -1 (-3250 1225)(-3775 1225);
FORCEPROP 2 LAST SIG_NAME PVDD11_S3_P0_TEMP1
J 2
(-3260 1235);
DISPLAY 0.489362 (-3260 1235);
FORCEPROP 2 LASTPROP $XRERR UNIQUE?
J 0
(-3500 1235);
DISPLAY 0.638298 (-3500 1235);
PAINT MONO (-3500 1235);
DISPLAY INVISIBLE (-3500 1235);
WIRE 16 -1 (-3775 1975)(-2950 1975);
FORCEPROP 2 LAST SIG_NAME NC_PVDD11_S3_P0_PWM8
J 2
(-3210 1985);
DISPLAY 0.489362 (-3210 1985);
FORCEPROP 2 LASTPROP $XRERR UNIQUE?
J 0
(-2920 1975);
DISPLAY 0.638298 (-2920 1975);
PAINT MONO (-2920 1975);
DISPLAY INVISIBLE (-2920 1975);
WIRE 16 -1 (-3250 1875)(-3775 1875);
FORCEPROP 2 LAST SIG_NAME NC_PVDD11_S3_P0_IMON8
J 2
(-3235 1885);
DISPLAY 0.489362 (-3235 1885);
FORCEPROP 2 LASTPROP $XRERR UNIQUE?
J 0
(-3475 1885);
DISPLAY 0.638298 (-3475 1885);
PAINT MONO (-3475 1885);
DISPLAY INVISIBLE (-3475 1885);
WIRE 16 -1 (-6100 6125)(-6675 6125);
FORCEPROP 2 LAST SIG_NAME PWRGD_PVDD11_S3_P0
J 2
(-6285 6135);
DISPLAY 0.489362 (-6285 6135);
WIRE 16 -1 (-6175 4675)(-6500 4675);
FORCEPROP 2 LAST SIG_NAME PVDD11_S3_P0_PMALERT
J 2
(-6335 4685);
DISPLAY 0.489362 (-6335 4685);
WIRE 16 -1 (-6500 4675)(-6500 4600);
WIRE 16 -1 (-6500 4675)(-6800 4675);
WIRE 16 -1 (-6175 4825)(-6800 4825);
FORCEPROP 2 LAST SIG_NAME SMB_SCM_2_R6_SDA
J 2
(-6385 4835);
DISPLAY 0.489362 (-6385 4835);
WIRE 16 -1 (-6375 2125)(-6975 2125);
FORCEPROP 2 LAST SIG_NAME PVDD11_S3_P0_OCP_N
J 2
(-6510 2135);
DISPLAY 0.489362 (-6510 2135);
WIRE 16 -1 (-6175 4975)(-6800 4975);
FORCEPROP 2 LAST SIG_NAME SMB_SCM_2_R6_SCL
J 2
(-6385 4985);
DISPLAY 0.489362 (-6385 4985);
WIRE 16 -1 (-6100 5975)(-6675 5975);
FORCEPROP 2 LAST SIG_NAME PVDD11_S3_P0_EN
J 2
(-6310 5985);
DISPLAY 0.489362 (-6310 5985);
WIRE 16 -1 (-900 1625)(-1600 1625);
FORCEPROP 2 LAST SIG_NAME PVDD11_S3_P0_RESET_N
J 2
(-910 1635);
DISPLAY 0.489362 (-910 1635);
CIRCLE (-6150 4100)(-6039 4100);
PAINT YELLOW (-6150 4100);
DOT 1 (-6000 2125);
DOT 1 (-5400 675);
DOT 1 (-3475 925);
DOT 1 (-2175 1625);
DOT 1 (-5400 2725);
DOT 1 (-5775 4075);
DOT 1 (-6075 5225);
DOT 1 (-6075 5525);
DOT 1 (-3425 5825);
DOT 1 (-6900 3825);
DOT 1 (-5775 3825);
DOT 1 (-6975 850);
DOT 1 (-6550 850);
DOT 1 (-6900 4075);
DOT 1 (-5725 675);
DOT 1 (-5725 6125);
DOT 1 (-5725 5975);
DOT 1 (-5725 6400);
DOT 1 (-2075 1625);
DOT 1 (-3025 5825);
DOT 1 (-3425 6300);
DOT 1 (-3025 6300);
DOT 1 (-6500 4675);
FORCENOTE
VR
(-9100 575) 0;
DISPLAY LEFT (-9100 575);
DISPLAY 0.808511 (-9100 575);
PAINT WHITE (-9100 575);
FORCENOTE
2ND SOURCE:INFENEON BOM
(-2025 4550) 0;
DISPLAY LEFT (-2025 4550);
DISPLAY 1.276596 (-2025 4550);
PAINT WHITE (-2025 4550);
FORCENOTE
PU21 = TBD/MP2856GUT-0021-Z
(-2025 3425) 0;
DISPLAY LEFT (-2025 3425);
DISPLAY 1.021277 (-2025 3425);
PAINT WHITE (-2025 3425);
FORCENOTE
PR3  = CS00002JB13
(-2025 3350) 0;
DISPLAY LEFT (-2025 3350);
DISPLAY 1.021277 (-2025 3350);
PAINT WHITE (-2025 3350);
FORCENOTE
PR37,PR33,PR34,PR35,PR419,PR36 = EMPTY
(-2025 3275) 0;
DISPLAY LEFT (-2025 3275);
DISPLAY 1.021277 (-2025 3275);
PAINT WHITE (-2025 3275);
FORCENOTE
PC194,PR113,PC193 = EMPTY
(-2025 3200) 0;
DISPLAY LEFT (-2025 3200);
DISPLAY 1.021277 (-2025 3200);
PAINT WHITE (-2025 3200);
FORCENOTE
PR126 = CS33402FB06
(-2025 3125) 0;
DISPLAY LEFT (-2025 3125);
DISPLAY 1.021277 (-2025 3125);
PAINT WHITE (-2025 3125);
FORCENOTE
PR125 = CS37502FB05
(-2025 3050) 0;
DISPLAY LEFT (-2025 3050);
DISPLAY 1.021277 (-2025 3050);
PAINT WHITE (-2025 3050);
FORCENOTE
PR601 = CS24992FB07
(-2025 2975) 0;
DISPLAY LEFT (-2025 2975);
DISPLAY 1.021277 (-2025 2975);
PAINT WHITE (-2025 2975);
FORCENOTE
PC198 = CH31004KB17
(-2025 2900) 0;
DISPLAY LEFT (-2025 2900);
DISPLAY 1.021277 (-2025 2900);
PAINT WHITE (-2025 2900);
FORCENOTE
PC5   = CH21006JB10
(-2025 2825) 0;
DISPLAY LEFT (-2025 2825);
DISPLAY 1.021277 (-2025 2825);
PAINT WHITE (-2025 2825);
FORCENOTE
PC199=CH5103KEB01
(-2025 2750) 0;
DISPLAY LEFT (-2025 2750);
DISPLAY 1.021277 (-2025 2750);
PAINT WHITE (-2025 2750);
FORCENOTE
PR37,PR33,PR34,PR35 = EMPTY
(-2025 4250) 0;
DISPLAY LEFT (-2025 4250);
DISPLAY 1.021277 (-2025 4250);
PAINT WHITE (-2025 4250);
FORCENOTE
PU21 = TBD/XDPE19283B
(-2025 4475) 0;
DISPLAY LEFT (-2025 4475);
DISPLAY 1.021277 (-2025 4475);
PAINT WHITE (-2025 4475);
FORCENOTE
TRACE WIDTH = 10MIL
(-7875 3500) 0;
DISPLAY LEFT (-7875 3500);
DISPLAY 0.808511 (-7875 3500);
PAINT WHITE (-7875 3500);
FORCENOTE
INFINEON
(-9100 375) 0;
DISPLAY LEFT (-9100 375);
DISPLAY 0.638298 (-9100 375);
PAINT WHITE (-9100 375);
FORCENOTE
RENESAS
(-9100 475) 0;
DISPLAY LEFT (-9100 475);
DISPLAY 0.638298 (-9100 475);
PAINT WHITE (-9100 475);
FORCENOTE
TDC=65A
(-1775 6250) 0;
DISPLAY LEFT (-1775 6250);
DISPLAY 0.936170 (-1775 6250);
PAINT WHITE (-1775 6250);
FORCENOTE
EDC=80A
(-1775 6175) 0;
DISPLAY LEFT (-1775 6175);
DISPLAY 0.936170 (-1775 6175);
PAINT WHITE (-1775 6175);
FORCENOTE
DIFFERENTIAL PAIR
(-7875 3575) 0;
DISPLAY LEFT (-7875 3575);
DISPLAY 0.808511 (-7875 3575);
PAINT WHITE (-7875 3575);
FORCENOTE
PC193 = CH3104J1B00
(-2025 3725) 0;
DISPLAY LEFT (-2025 3725);
DISPLAY 1.021277 (-2025 3725);
PAINT WHITE (-2025 3725);
FORCENOTE
PC194 = CH12206KB14
(-2025 3800) 0;
DISPLAY LEFT (-2025 3800);
DISPLAY 1.021277 (-2025 3800);
PAINT WHITE (-2025 3800);
FORCENOTE
PR121 = CS01002FB07
(-2025 4100) 0;
DISPLAY LEFT (-2025 4100);
DISPLAY 1.021277 (-2025 4100);
PAINT WHITE (-2025 4100);
FORCENOTE
PR419,PR36,PR412 = EMPTY
(-2025 4175) 0;
DISPLAY LEFT (-2025 4175);
DISPLAY 1.021277 (-2025 4175);
PAINT WHITE (-2025 4175);
FORCENOTE
PR126 = CS22672FB03
(-2025 4025) 0;
DISPLAY LEFT (-2025 4025);
DISPLAY 1.021277 (-2025 4025);
PAINT WHITE (-2025 4025);
FORCENOTE
3RD SOURCE:MPS BOM
(-2025 3500) 0;
DISPLAY LEFT (-2025 3500);
DISPLAY 1.276596 (-2025 3500);
PAINT WHITE (-2025 3500);
FORCENOTE
PC199 = CH5103KEB01
(-2025 3950) 0;
DISPLAY LEFT (-2025 3950);
DISPLAY 1.021277 (-2025 3950);
PAINT WHITE (-2025 3950);
FORCENOTE
PC198 = CH11006JB00
(-2025 3875) 0;
DISPLAY LEFT (-2025 3875);
DISPLAY 1.021277 (-2025 3875);
PAINT WHITE (-2025 3875);
FORCENOTE
PR113 = CS25362FB02
(-2025 4400) 0;
DISPLAY LEFT (-2025 4400);
DISPLAY 1.021277 (-2025 4400);
PAINT WHITE (-2025 4400);
FORCENOTE
PR3 = CS21002FB06
(-2025 4325) 0;
DISPLAY LEFT (-2025 4325);
DISPLAY 1.021277 (-2025 4325);
PAINT WHITE (-2025 4325);
FORCENOTE
PU21 = TBD/RAA229621GNP#HA0
(-2025 4725) 0;
DISPLAY LEFT (-2025 4725);
DISPLAY 1.021277 (-2025 4725);
PAINT WHITE (-2025 4725);
FORCENOTE
PVDD11_S3_P0 SPECFICATION
(-1775 6525) 0;
DISPLAY LEFT (-1775 6525);
DISPLAY 1.276596 (-1775 6525);
PAINT WHITE (-1775 6525);
FORCENOTE
OCP=96A (EDC*1.2)
(-1775 6100) 0;
DISPLAY LEFT (-1775 6100);
DISPLAY 0.936170 (-1775 6100);
PAINT WHITE (-1775 6100);
FORCENOTE
OUTPUT VOLTAGE=1.1V
(-1775 6400) 0;
DISPLAY LEFT (-1775 6400);
DISPLAY 0.936170 (-1775 6400);
PAINT WHITE (-1775 6400);
FORCENOTE
DC & AC=1.045-1.155V
(-1775 6325) 0;
DISPLAY LEFT (-1775 6325);
DISPLAY 0.936170 (-1775 6325);
PAINT WHITE (-1775 6325);
FORCENOTE
MAX LOAD STEP=25A
(-1775 6025) 0;
DISPLAY LEFT (-1775 6025);
DISPLAY 0.936170 (-1775 6025);
PAINT WHITE (-1775 6025);
FORCENOTE
MAX LOAD RELEASE=35A
(-1775 5950) 0;
DISPLAY LEFT (-1775 5950);
DISPLAY 0.936170 (-1775 5950);
PAINT WHITE (-1775 5950);
FORCENOTE
WORK FREQUENCY=600KHZ
(-1775 5875) 0;
DISPLAY LEFT (-1775 5875);
DISPLAY 0.936170 (-1775 5875);
PAINT WHITE (-1775 5875);
FORCENOTE
EFFICIENCY > 90% @TDC
(-1775 5800) 0;
DISPLAY LEFT (-1775 5800);
DISPLAY 0.936170 (-1775 5800);
PAINT WHITE (-1775 5800);
FORCENOTE
IRM REV1.09
(-1775 5725) 0;
DISPLAY LEFT (-1775 5725);
DISPLAY 0.936170 (-1775 5725);
PAINT WHITE (-1775 5725);
FORCENOTE
0X63
(-8650 475) 0;
DISPLAY LEFT (-8650 475);
DISPLAY 0.638298 (-8650 475);
PAINT WHITE (-8650 475);
FORCENOTE
ADDRESS(7-BIT)
(-8850 575) 0;
DISPLAY LEFT (-8850 575);
DISPLAY 0.808511 (-8850 575);
PAINT WHITE (-8850 575);
FORCENOTE
MPS
(-9100 275) 0;
DISPLAY LEFT (-9100 275);
DISPLAY 0.638298 (-9100 275);
PAINT WHITE (-9100 275);
FORCENOTE
0X49
(-8650 375) 0;
DISPLAY LEFT (-8650 375);
DISPLAY 0.638298 (-8650 375);
PAINT WHITE (-8650 375);
FORCENOTE
0/3.09K
(-8300 475) 0;
DISPLAY LEFT (-8300 475);
DISPLAY 0.638298 (-8300 475);
PAINT WHITE (-8300 475);
FORCENOTE
/4.64K
(-8300 375) 0;
DISPLAY LEFT (-8300 375);
DISPLAY 0.638298 (-8300 375);
PAINT WHITE (-8300 375);
FORCENOTE
CONFIG/R
(-8300 575) 0;
DISPLAY LEFT (-8300 575);
DISPLAY 0.808511 (-8300 575);
PAINT WHITE (-8300 575);
FORCENOTE
0X49
(-8650 275) 0;
DISPLAY LEFT (-8650 275);
DISPLAY 0.638298 (-8650 275);
PAINT WHITE (-8650 275);
FORCENOTE
/21.5K
(-8300 275) 0;
DISPLAY LEFT (-8300 275);
DISPLAY 0.638298 (-8300 275);
PAINT WHITE (-8300 275);
FORCENOTE
PMBUS ADDRESS AND CONFIG
(-9200 700) 0;
DISPLAY LEFT (-9200 700);
DISPLAY 1.170213 (-9200 700);
PAINT WHITE (-9200 700);
FORCENOTE
TRACE SPACING = 5MIL
(-7875 3425) 0;
DISPLAY LEFT (-7875 3425);
DISPLAY 0.808511 (-7875 3425);
PAINT WHITE (-7875 3425);
FORCENOTE
BOM NOTE
(-2025 4900) 0;
DISPLAY LEFT (-2025 4900);
DISPLAY 1.595745 (-2025 4900);
PAINT WHITE (-2025 4900);
FORCENOTE
MAIN SOURCE:RENESAS BOM
(-2025 4800) 0;
DISPLAY LEFT (-2025 4800);
DISPLAY 1.276596 (-2025 4800);
PAINT WHITE (-2025 4800);
QUIT
